G04 ================== begin FILE IDENTIFICATION RECORD ==================*
G04 Layout Name:  t6m_pdb_d_0928_1400_274.brd*
G04 Film Name:    vcc1*
G04 File Format:  Gerber RS274X*
G04 File Origin:  Cadence Allegro 16.3-S048*
G04 Origin Date:  Tue Nov 26 11:01:51 2013*
G04 *
G04 Layer:  DRAWING FORMAT/TITLE_BLOCK*
G04 Layer:  VIA CLASS/VCC1*
G04 Layer:  PIN/VCC1*
G04 Layer:  MANUFACTURING/PHOTOPLOT_OUTLINE*
G04 Layer:  ETCH/VCC1*
G04 Layer:  DRAWING FORMAT/TITLE_DATA_VCC1*
G04 *
G04 Offset:    (0.00 0.00)*
G04 Mirror:    No*
G04 Mode:      Negative*
G04 Rotation:  0*
G04 FullContactRelief:  No*
G04 UndefLineWidth:     6.00*
G04 ================== end FILE IDENTIFICATION RECORD ====================*
%FSLAX25Y25*MOIN*%
%IR0*IPPOS*OFA0.00000B0.00000*MIA0B0*SFA1.00000B1.00000*%
%ADD11C,.03*%
%ADD28C,.04*%
%ADD31C,.05*%
%ADD22C,.042*%
%ADD16C,.06*%
%ADD25C,.064*%
%ADD15C,.083*%
%ADD13C,.056*%
%ADD17C,.048*%
%AMMACRO29*
4,1,36,0.0,.009,
.001563,.008863,
.003078,.008457,
.0045,.007794,
.005785,.006894,
.006894,.005785,
.007794,.0045,
.008457,.003078,
.008863,.001563,
.009,0.0,
.008863,-.001563,
.008457,-.003078,
.007794,-.0045,
.006894,-.005785,
.005785,-.006894,
.0045,-.007794,
.003078,-.008457,
.001563,-.008863,
0.0,-.009,
-.001563,-.008863,
-.003078,-.008457,
-.0045,-.007794,
-.005785,-.006894,
-.006894,-.005785,
-.007794,-.0045,
-.008457,-.003078,
-.008863,-.001563,
-.009,0.0,
-.008863,.001563,
-.008457,.003078,
-.007794,.0045,
-.006894,.005785,
-.005785,.006894,
-.0045,.007794,
-.003078,.008457,
-.001563,.008863,
0.0,.009,
90.*
%
%ADD29MACRO29*%
%ADD20C,.077*%
%ADD10C,.059*%
%AMMACRO30*
4,1,36,0.0,.009,
.001563,.008863,
.003078,.008457,
.0045,.007794,
.005785,.006894,
.006894,.005785,
.007794,.0045,
.008457,.003078,
.008863,.001563,
.009,0.0,
.008863,-.001563,
.008457,-.003078,
.007794,-.0045,
.006894,-.005785,
.005785,-.006894,
.0045,-.007794,
.003078,-.008457,
.001563,-.008863,
0.0,-.009,
-.001563,-.008863,
-.003078,-.008457,
-.0045,-.007794,
-.005785,-.006894,
-.006894,-.005785,
-.007794,-.0045,
-.008457,-.003078,
-.008863,-.001563,
-.009,0.0,
-.008863,.001563,
-.008457,.003078,
-.007794,.0045,
-.006894,.005785,
-.005785,.006894,
-.0045,.007794,
-.003078,.008457,
-.001563,.008863,
0.0,.009,
0.0*
%
%ADD30MACRO30*%
%ADD37O,.235X.274*%
%ADD19C,.125*%
%ADD12C,.162*%
%ADD36C,.235*%
%ADD38C,.345*%
%ADD27C,.129*%
%ADD14C,.156*%
%AMMACRO18*
4,1,36,0.0,.013,
-.002257,.012803,
-.004446,.012216,
-.0065,.011258,
-.008356,.009959,
-.009959,.008356,
-.011258,.0065,
-.012216,.004446,
-.012803,.002257,
-.013,0.0,
-.012803,-.002257,
-.012216,-.004446,
-.011258,-.0065,
-.009959,-.008356,
-.008356,-.009959,
-.0065,-.011258,
-.004446,-.012216,
-.002257,-.012803,
0.0,-.013,
.002257,-.012803,
.004446,-.012216,
.0065,-.011258,
.008356,-.009959,
.009959,-.008356,
.011258,-.0065,
.012216,-.004446,
.012803,-.002257,
.013,0.0,
.012803,.002257,
.012216,.004446,
.011258,.0065,
.009959,.008356,
.008356,.009959,
.0065,.011258,
.004446,.012216,
.002257,.012803,
0.0,.013,
270.*
%
%ADD18MACRO18*%
%AMMACRO35*
4,1,36,0.0,.009,
.001563,.008863,
.003078,.008457,
.0045,.007794,
.005785,.006894,
.006894,.005785,
.007794,.0045,
.008457,.003078,
.008863,.001563,
.009,0.0,
.008863,-.001563,
.008457,-.003078,
.007794,-.0045,
.006894,-.005785,
.005785,-.006894,
.0045,-.007794,
.003078,-.008457,
.001563,-.008863,
0.0,-.009,
-.001563,-.008863,
-.003078,-.008457,
-.0045,-.007794,
-.005785,-.006894,
-.006894,-.005785,
-.007794,-.0045,
-.008457,-.003078,
-.008863,-.001563,
-.009,0.0,
-.008863,.001563,
-.008457,.003078,
-.007794,.0045,
-.006894,.005785,
-.005785,.006894,
-.0045,.007794,
-.003078,.008457,
-.001563,.008863,
0.0,.009,
270.*
%
%ADD35MACRO35*%
%AMMACRO33*
4,1,36,0.0,.009,
.001563,.008863,
.003078,.008457,
.0045,.007794,
.005785,.006894,
.006894,.005785,
.007794,.0045,
.008457,.003078,
.008863,.001563,
.009,0.0,
.008863,-.001563,
.008457,-.003078,
.007794,-.0045,
.006894,-.005785,
.005785,-.006894,
.0045,-.007794,
.003078,-.008457,
.001563,-.008863,
0.0,-.009,
-.001563,-.008863,
-.003078,-.008457,
-.0045,-.007794,
-.005785,-.006894,
-.006894,-.005785,
-.007794,-.0045,
-.008457,-.003078,
-.008863,-.001563,
-.009,0.0,
-.008863,.001563,
-.008457,.003078,
-.007794,.0045,
-.006894,.005785,
-.005785,.006894,
-.0045,.007794,
-.003078,.008457,
-.001563,.008863,
0.0,.009,
180.*
%
%ADD33MACRO33*%
%AMMACRO34*
4,1,36,0.0,.014,
.002431,.013787,
.004788,.013156,
.007,.012124,
.008999,.010725,
.010725,.008999,
.012124,.007,
.013156,.004788,
.013787,.002431,
.014,0.0,
.013787,-.002431,
.013156,-.004788,
.012124,-.007,
.010725,-.008999,
.008999,-.010725,
.007,-.012124,
.004788,-.013156,
.002431,-.013787,
0.0,-.014,
-.002431,-.013787,
-.004788,-.013156,
-.007,-.012124,
-.008999,-.010725,
-.010725,-.008999,
-.012124,-.007,
-.013156,-.004788,
-.013787,-.002431,
-.014,0.0,
-.013787,.002431,
-.013156,.004788,
-.012124,.007,
-.010725,.008999,
-.008999,.010725,
-.007,.012124,
-.004788,.013156,
-.002431,.013787,
0.0,.014,
180.*
%
%ADD34MACRO34*%
%ADD23C,.188*%
%AMMACRO24*
4,1,36,0.0,.004,
.000695,.003939,
.001368,.003759,
.002,.003464,
.002571,.003064,
.003064,.002571,
.003464,.002,
.003759,.001368,
.003939,.000695,
.004,0.0,
.003939,-.000695,
.003759,-.001368,
.003464,-.002,
.003064,-.002571,
.002571,-.003064,
.002,-.003464,
.001368,-.003759,
.000695,-.003939,
0.0,-.004,
-.000695,-.003939,
-.001368,-.003759,
-.002,-.003464,
-.002571,-.003064,
-.003064,-.002571,
-.003464,-.002,
-.003759,-.001368,
-.003939,-.000695,
-.004,0.0,
-.003939,.000695,
-.003759,.001368,
-.003464,.002,
-.003064,.002571,
-.002571,.003064,
-.002,.003464,
-.001368,.003759,
-.000695,.003939,
0.0,.004,
0.0*
%
%ADD24MACRO24*%
%AMMACRO26*
4,1,16,.02584,.01524,
.028094,.010521,
.029494,.005483,
.029998,.000278,
.029591,-.004935,
.028284,-.009999,
.026118,-.014758,
.02584,-.01524,
.03092,-.02032,
.033979,-.014642,
.036005,-.008519,
.036938,-.002138,
.036748,.004309,
.035441,.010625,
.033058,.016618,
.03092,.02032,
.02584,.01524,
270.*
4,1,16,.01524,-.02584,
.010521,-.028094,
.005483,-.029494,
.000278,-.029998,
-.004935,-.029591,
-.009999,-.028284,
-.014758,-.026118,
-.01524,-.02584,
-.02032,-.03092,
-.014642,-.033979,
-.008519,-.036005,
-.002138,-.036938,
.004309,-.036748,
.010625,-.035441,
.016618,-.033058,
.02032,-.03092,
.01524,-.02584,
270.*
4,1,16,-.02584,-.01524,
-.028094,-.010521,
-.029494,-.005483,
-.029998,-.000278,
-.029591,.004935,
-.028284,.009999,
-.026118,.014758,
-.02584,.01524,
-.03092,.02032,
-.033979,.014642,
-.036005,.008519,
-.036938,.002138,
-.036748,-.004309,
-.035441,-.010625,
-.033058,-.016618,
-.03092,-.02032,
-.02584,-.01524,
270.*
4,1,16,-.01524,.02584,
-.010521,.028094,
-.005483,.029494,
-.000278,.029998,
.004935,.029591,
.009999,.028284,
.014758,.026118,
.01524,.02584,
.02032,.03092,
.014642,.033979,
.008519,.036005,
.002138,.036938,
-.004309,.036748,
-.010625,.035441,
-.016618,.033058,
-.02032,.03092,
-.01524,.02584,
270.*
%
%ADD26MACRO26*%
%AMMACRO32*
4,1,15,.02291,.0123,
.024698,.008135,
.025735,.003723,
.025991,-.000803,
.025456,-.005304,
.024149,-.009644,
.02291,-.0123,
.02803,-.01742,
.030629,-.012288,
.032298,-.006783,
.032985,-.001071,
.03267,.004673,
.031362,.010275,
.029101,.015565,
.02803,.01742,
.02291,.0123,
180.*
4,1,15,.0123,-.02291,
.008135,-.024698,
.003723,-.025735,
-.000803,-.025991,
-.005304,-.025456,
-.009644,-.024149,
-.0123,-.02291,
-.01742,-.02803,
-.012288,-.030629,
-.006783,-.032298,
-.001071,-.032985,
.004673,-.03267,
.010275,-.031362,
.015565,-.029101,
.01742,-.02803,
.0123,-.02291,
180.*
4,1,15,-.02291,-.0123,
-.024698,-.008135,
-.025735,-.003723,
-.025991,.000803,
-.025456,.005304,
-.024149,.009644,
-.02291,.0123,
-.02803,.01742,
-.030629,.012288,
-.032298,.006783,
-.032985,.001071,
-.03267,-.004673,
-.031362,-.010275,
-.029101,-.015565,
-.02803,-.01742,
-.02291,-.0123,
180.*
4,1,15,-.0123,.02291,
-.008135,.024698,
-.003723,.025735,
.000803,.025991,
.005304,.025456,
.009644,.024149,
.0123,.02291,
.01742,.02803,
.012288,.030629,
.006783,.032298,
.001071,.032985,
-.004673,.03267,
-.010275,.031362,
-.015565,.029101,
-.01742,.02803,
-.0123,.02291,
180.*
%
%ADD32MACRO32*%
%AMMACRO21*
4,1,17,.03056,.01996,
.033562,.01435,
.035544,.008304,
.036446,.002006,
.03624,-.004353,
.034934,-.01058,
.032566,-.016486,
.03056,-.01996,
.0356,-.025,
.0394,-.018438,
.042004,-.011316,
.043331,-.003851,
.043341,.003732,
.042034,.011201,
.039451,.018331,
.035668,.024903,
.0356,.025,
.03056,.01996,
270.*
4,1,17,.01996,-.03056,
.01435,-.033562,
.008304,-.035544,
.002006,-.036446,
-.004353,-.03624,
-.01058,-.034934,
-.016486,-.032566,
-.01996,-.03056,
-.025,-.0356,
-.018438,-.0394,
-.011316,-.042004,
-.003851,-.043331,
.003732,-.043341,
.011201,-.042034,
.018331,-.039451,
.024903,-.035668,
.025,-.0356,
.01996,-.03056,
270.*
4,1,17,-.03056,-.01996,
-.033562,-.01435,
-.035544,-.008304,
-.036446,-.002006,
-.03624,.004353,
-.034934,.01058,
-.032566,.016486,
-.03056,.01996,
-.0356,.025,
-.0394,.018438,
-.042004,.011316,
-.043331,.003851,
-.043341,-.003732,
-.042034,-.011201,
-.039451,-.018331,
-.035668,-.024903,
-.0356,-.025,
-.03056,-.01996,
270.*
4,1,17,-.01996,.03056,
-.01435,.033562,
-.008304,.035544,
-.002006,.036446,
.004353,.03624,
.01058,.034934,
.016486,.032566,
.01996,.03056,
.025,.0356,
.018438,.0394,
.011316,.042004,
.003851,.043331,
-.003732,.043341,
-.011201,.042034,
-.018331,.039451,
-.024903,.035668,
-.025,.0356,
-.01996,.03056,
270.*
%
%ADD21MACRO21*%
%ADD39C,.006*%
%ADD42C,.4138*%
%ADD51C,.24506*%
%ADD50C,.13238*%
%ADD47C,.16406*%
%ADD49C,.12717*%
%ADD45C,.13266*%
%ADD40C,.40492*%
%ADD48C,.15806*%
%ADD46C,.35606*%
%ADD43C,.41384*%
%ADD44C,.41386*%
%ADD41C,.41378*%
G75*
%LPD*%
G75*
G36*
G01X-723776Y-489221D02*
X1782976D01*
Y2987387D01*
X-723776D01*
Y-489221D01*
G37*
%LPC*%
G75*
G36*
G01X104331Y4000D02*
G02X102425Y5906I0J1906D01*
G01Y9843D01*
G03X92520Y19748I-9905J0D01*
G01X77515D01*
G03X72923I-2296J-996D01*
G01X26549D01*
G02X26217Y19874I0J500D01*
G03X24221I-998J-1122D01*
G02X23889Y19748I-332J374D01*
G01X5906D01*
G02X4000Y21654I0J1906D01*
G01Y50707D01*
X4124Y51033D01*
X4173Y51094D01*
G03Y52974I-1172J940D01*
G01X4124Y53035D01*
X4000Y53361D01*
Y54967D01*
G02X5841Y55509I1000J1D01*
G03Y64397I6894J4444D01*
G02X4000Y64939I-841J541D01*
G01Y98707D01*
X4124Y99033D01*
X4173Y99094D01*
G03Y100974I-1172J940D01*
G01X4124Y101035D01*
X4000Y101361D01*
Y148707D01*
X4124Y149033D01*
X4173Y149094D01*
G03Y150974I-1172J940D01*
G01X4124Y151035D01*
X4000Y151361D01*
Y176990D01*
G02X5841Y177532I1000J1D01*
G03Y186420I6894J4444D01*
G02X4000Y186962I-841J541D01*
G01Y198707D01*
X4124Y199033D01*
X4173Y199094D01*
G03Y200974I-1172J940D01*
G01X4124Y201035D01*
X4000Y201361D01*
Y248707D01*
X4124Y249033D01*
X4173Y249094D01*
G03Y250974I-1172J940D01*
G01X4124Y251035D01*
X4000Y251361D01*
Y263825D01*
G02X5841Y264367I1000J1D01*
G03Y273255I6894J4444D01*
G02X4000Y273797I-841J541D01*
G01Y298707D01*
X4124Y299033D01*
X4173Y299094D01*
G03Y300974I-1172J940D01*
G01X4124Y301035D01*
X4000Y301361D01*
Y348707D01*
X4124Y349033D01*
X4173Y349094D01*
G03Y350974I-1172J940D01*
G01X4124Y351035D01*
X4000Y351361D01*
Y385848D01*
G02X5841Y386390I1000J1D01*
G03Y395278I6894J4444D01*
G02X4000Y395820I-841J541D01*
G01Y398707D01*
X4124Y399033D01*
X4173Y399094D01*
G03Y400974I-1172J940D01*
G01X4124Y401035D01*
X4000Y401361D01*
Y448707D01*
X4124Y449033D01*
X4173Y449094D01*
G03Y450974I-1172J940D01*
G01X4124Y451035D01*
X4000Y451361D01*
Y498707D01*
X4124Y499033D01*
X4173Y499094D01*
G03Y500974I-1172J940D01*
G01X4124Y501035D01*
X4000Y501361D01*
Y548707D01*
X4124Y549033D01*
X4173Y549094D01*
G03Y550974I-1172J940D01*
G01X4124Y551035D01*
X4000Y551361D01*
Y598707D01*
X4124Y599033D01*
X4173Y599094D01*
G03Y600974I-1172J940D01*
G01X4124Y601035D01*
X4000Y601361D01*
Y648707D01*
X4124Y649033D01*
X4173Y649094D01*
G03Y650974I-1172J940D01*
G01X4124Y651035D01*
X4000Y651361D01*
Y698707D01*
X4124Y699033D01*
X4173Y699094D01*
G03Y700974I-1172J940D01*
G01X4124Y701035D01*
X4000Y701361D01*
Y748707D01*
X4124Y749033D01*
X4173Y749094D01*
G03Y750974I-1172J940D01*
G01X4124Y751035D01*
X4000Y751361D01*
Y798707D01*
X4124Y799033D01*
X4173Y799094D01*
G03Y800974I-1172J940D01*
G01X4124Y801035D01*
X4000Y801361D01*
Y848707D01*
X4124Y849033D01*
X4173Y849094D01*
G03Y850974I-1172J940D01*
G01X4124Y851035D01*
X4000Y851361D01*
Y898707D01*
X4124Y899033D01*
X4173Y899094D01*
G03Y900974I-1172J940D01*
G01X4124Y901035D01*
X4000Y901361D01*
Y948707D01*
X4124Y949033D01*
X4173Y949094D01*
G03Y950974I-1172J940D01*
G01X4124Y951035D01*
X4000Y951361D01*
Y998707D01*
X4124Y999033D01*
X4173Y999094D01*
G03Y1000974I-1172J940D01*
G01X4124Y1001035D01*
X4000Y1001361D01*
Y1048707D01*
X4124Y1049033D01*
X4173Y1049094D01*
G03Y1050974I-1172J940D01*
G01X4124Y1051035D01*
X4000Y1051361D01*
Y1098707D01*
X4124Y1099033D01*
X4173Y1099094D01*
G03Y1100974I-1172J940D01*
G01X4124Y1101035D01*
X4000Y1101361D01*
Y1148707D01*
X4124Y1149033D01*
X4173Y1149094D01*
G03Y1150974I-1172J940D01*
G01X4124Y1151035D01*
X4000Y1151361D01*
Y1198707D01*
X4124Y1199033D01*
X4173Y1199094D01*
G03Y1200974I-1172J940D01*
G01X4124Y1201035D01*
X4000Y1201361D01*
Y1248707D01*
X4124Y1249033D01*
X4173Y1249094D01*
G03Y1250974I-1172J940D01*
G01X4124Y1251035D01*
X4000Y1251361D01*
Y1298707D01*
X4124Y1299033D01*
X4173Y1299094D01*
G03Y1300974I-1172J940D01*
G01X4124Y1301035D01*
X4000Y1301361D01*
Y1348707D01*
X4124Y1349033D01*
X4173Y1349094D01*
G03Y1350974I-1172J940D01*
G01X4124Y1351035D01*
X4000Y1351361D01*
Y1398707D01*
X4124Y1399033D01*
X4173Y1399094D01*
G03Y1400974I-1172J940D01*
G01X4124Y1401035D01*
X4000Y1401361D01*
Y1448707D01*
X4124Y1449033D01*
X4173Y1449094D01*
G03Y1450974I-1172J940D01*
G01X4124Y1451035D01*
X4000Y1451361D01*
Y1498707D01*
X4124Y1499033D01*
X4173Y1499094D01*
G03Y1500974I-1172J940D01*
G01X4124Y1501035D01*
X4000Y1501361D01*
Y1548707D01*
X4124Y1549033D01*
X4173Y1549094D01*
G03Y1550974I-1172J940D01*
G01X4124Y1551035D01*
X4000Y1551361D01*
Y1593269D01*
X4124Y1593595D01*
X4174Y1593657D01*
G03Y1595547I-1168J945D01*
G01X4124Y1595609D01*
X4000Y1595935D01*
Y1608826D01*
X4126Y1609154D01*
X4176Y1609217D01*
X4178Y1609219D01*
G03Y1611111I-1166J946D01*
G01X4176Y1611113D01*
X4126Y1611176D01*
X4000Y1611504D01*
Y1648707D01*
X4124Y1649033D01*
X4173Y1649094D01*
G03Y1650974I-1172J940D01*
G01X4124Y1651035D01*
X4000Y1651361D01*
Y1698707D01*
X4124Y1699033D01*
X4173Y1699094D01*
G03Y1700974I-1172J940D01*
G01X4124Y1701035D01*
X4000Y1701361D01*
Y1748707D01*
X4124Y1749033D01*
X4173Y1749094D01*
G03Y1750974I-1172J940D01*
G01X4124Y1751035D01*
X4000Y1751361D01*
Y1798707D01*
X4124Y1799033D01*
X4173Y1799094D01*
G03Y1800974I-1172J940D01*
G01X4124Y1801035D01*
X4000Y1801361D01*
Y1848707D01*
X4124Y1849033D01*
X4173Y1849094D01*
G03Y1850974I-1172J940D01*
G01X4124Y1851035D01*
X4000Y1851361D01*
Y1898707D01*
X4124Y1899033D01*
X4173Y1899094D01*
G03Y1900974I-1172J940D01*
G01X4124Y1901035D01*
X4000Y1901361D01*
Y1917305D01*
G02X5841Y1917847I1000J1D01*
G03Y1926735I6894J4444D01*
G02X4000Y1927277I-841J541D01*
G01Y1948707D01*
X4124Y1949033D01*
X4173Y1949094D01*
G03Y1950974I-1172J940D01*
G01X4124Y1951035D01*
X4000Y1951361D01*
Y1998707D01*
X4124Y1999033D01*
X4173Y1999094D01*
G03Y2000974I-1172J940D01*
G01X4124Y2001035D01*
X4000Y2001361D01*
Y2021675D01*
G02X5841Y2022217I1000J1D01*
G03Y2031105I6894J4444D01*
G02X4000Y2031647I-841J541D01*
G01Y2048707D01*
X4124Y2049033D01*
X4173Y2049094D01*
G03Y2050974I-1172J940D01*
G01X4124Y2051035D01*
X4000Y2051361D01*
Y2064961D01*
G02X5905Y2066866I1905J0D01*
G01X25507D01*
G02X25838Y2066741I0J-500D01*
G03X27828I995J1125D01*
G02X28159Y2066866I331J-375D01*
G01X75507D01*
G02X75838Y2066741I0J-500D01*
G03X77828I995J1125D01*
G02X78159Y2066866I331J-375D01*
G01X92520D01*
G03X102425Y2076772I0J9905D01*
G01Y2080709D01*
G02X104331Y2082614I1906J-1D01*
G01X108657D01*
X108984Y2082490D01*
X109046Y2082439D01*
G03X110936I945J1168D01*
G01X110998Y2082490D01*
X111325Y2082614D01*
X158657D01*
X158984Y2082490D01*
X159046Y2082439D01*
G03X160936I945J1168D01*
G01X160998Y2082490D01*
X161325Y2082614D01*
X208657D01*
X208984Y2082490D01*
X209046Y2082439D01*
G03X210936I945J1168D01*
G01X210998Y2082490D01*
X211325Y2082614D01*
X258657D01*
X258984Y2082490D01*
X259046Y2082439D01*
G03X260936I945J1168D01*
G01X260998Y2082490D01*
X261325Y2082614D01*
X308657D01*
X308984Y2082490D01*
X309046Y2082439D01*
G03X310936I945J1168D01*
G01X310998Y2082490D01*
X311325Y2082614D01*
X358657D01*
X358984Y2082490D01*
X359046Y2082439D01*
G03X360936I945J1168D01*
G01X360998Y2082490D01*
X361325Y2082614D01*
X397638D01*
G02X401512Y2078740I0J-3874D01*
G01Y2068434D01*
G02X401387Y2068103I-500J0D01*
G03Y2066113I1125J-995D01*
G02X401512Y2065782I-375J-331D01*
G01Y2018434D01*
G02X401387Y2018103I-500J0D01*
G03Y2016113I1125J-995D01*
G02X401512Y2015782I-375J-331D01*
G01Y1968434D01*
G02X401387Y1968103I-500J0D01*
G03Y1966113I1125J-995D01*
G02X401512Y1965782I-375J-331D01*
G01Y1918434D01*
G02X401387Y1918103I-500J0D01*
G03Y1916113I1125J-995D01*
G02X401512Y1915782I-375J-331D01*
G01Y1868434D01*
G02X401387Y1868103I-500J0D01*
G03Y1866113I1125J-995D01*
G02X401512Y1865782I-375J-331D01*
G01Y1818434D01*
G02X401387Y1818103I-500J0D01*
G03Y1816113I1125J-995D01*
G02X401512Y1815782I-375J-331D01*
G01Y1768434D01*
G02X401387Y1768103I-500J0D01*
G03Y1766113I1125J-995D01*
G02X401512Y1765782I-375J-331D01*
G01Y1718434D01*
G02X401387Y1718103I-500J0D01*
G03Y1716113I1125J-995D01*
G02X401512Y1715782I-375J-331D01*
G01Y1668434D01*
G02X401387Y1668103I-500J0D01*
G03Y1666113I1125J-995D01*
G02X401512Y1665782I-375J-331D01*
G01Y1618434D01*
G02X401387Y1618103I-500J0D01*
G03Y1616113I1125J-995D01*
G02X401512Y1615782I-375J-331D01*
G01Y1568434D01*
G02X401387Y1568103I-500J0D01*
G03Y1566113I1125J-995D01*
G02X401512Y1565782I-375J-331D01*
G01Y1518434D01*
G02X401387Y1518103I-500J0D01*
G03Y1516113I1125J-995D01*
G02X401512Y1515782I-375J-331D01*
G01Y1468434D01*
G02X401387Y1468103I-500J0D01*
G03Y1466113I1125J-995D01*
G02X401512Y1465782I-375J-331D01*
G01Y1418434D01*
G02X401387Y1418103I-500J0D01*
G03Y1416113I1125J-995D01*
G02X401512Y1415782I-375J-331D01*
G01Y1368434D01*
G02X401387Y1368103I-500J0D01*
G03Y1366113I1125J-995D01*
G02X401512Y1365782I-375J-331D01*
G01Y1318434D01*
G02X401387Y1318103I-500J0D01*
G03Y1316113I1125J-995D01*
G02X401512Y1315782I-375J-331D01*
G01Y1268434D01*
G02X401387Y1268103I-500J0D01*
G03Y1266113I1125J-995D01*
G02X401512Y1265782I-375J-331D01*
G01Y1218434D01*
G02X401387Y1218103I-500J0D01*
G03Y1216113I1125J-995D01*
G02X401512Y1215782I-375J-331D01*
G01Y1168434D01*
G02X401387Y1168103I-500J0D01*
G03Y1166113I1125J-995D01*
G02X401512Y1165782I-375J-331D01*
G01Y1118434D01*
G02X401387Y1118103I-500J0D01*
G03Y1116113I1125J-995D01*
G02X401512Y1115782I-375J-331D01*
G01Y1068434D01*
G02X401387Y1068103I-500J0D01*
G03Y1066113I1125J-995D01*
G02X401512Y1065782I-375J-331D01*
G01Y1018434D01*
G02X401387Y1018103I-500J0D01*
G03Y1016113I1125J-995D01*
G02X401512Y1015782I-375J-331D01*
G01Y968434D01*
G02X401387Y968103I-500J0D01*
G03Y966113I1125J-995D01*
G02X401512Y965782I-375J-331D01*
G01Y918434D01*
G02X401387Y918103I-500J0D01*
G03Y916113I1125J-995D01*
G02X401512Y915782I-375J-331D01*
G01Y868434D01*
G02X401387Y868103I-500J0D01*
G03Y866113I1125J-995D01*
G02X401512Y865782I-375J-331D01*
G01Y818434D01*
G02X401387Y818103I-500J0D01*
G03Y816113I1125J-995D01*
G02X401512Y815782I-375J-331D01*
G01Y768434D01*
G02X401387Y768103I-500J0D01*
G03Y766113I1125J-995D01*
G02X401512Y765782I-375J-331D01*
G01Y718434D01*
G02X401387Y718103I-500J0D01*
G03Y716113I1125J-995D01*
G02X401512Y715782I-375J-331D01*
G01Y668434D01*
G02X401387Y668103I-500J0D01*
G03Y666113I1125J-995D01*
G02X401512Y665782I-375J-331D01*
G01Y618434D01*
G02X401387Y618103I-500J0D01*
G03Y616113I1125J-995D01*
G02X401512Y615782I-375J-331D01*
G01Y568434D01*
G02X401387Y568103I-500J0D01*
G03Y566113I1125J-995D01*
G02X401512Y565782I-375J-331D01*
G01Y518434D01*
G02X401387Y518103I-500J0D01*
G03Y516113I1125J-995D01*
G02X401512Y515782I-375J-331D01*
G01Y468434D01*
G02X401387Y468103I-500J0D01*
G03Y466113I1125J-995D01*
G02X401512Y465782I-375J-331D01*
G01Y418434D01*
G02X401387Y418103I-500J0D01*
G03Y416113I1125J-995D01*
G02X401512Y415782I-375J-331D01*
G01Y368434D01*
G02X401387Y368103I-500J0D01*
G03Y366113I1125J-995D01*
G02X401512Y365782I-375J-331D01*
G01Y318434D01*
G02X401387Y318103I-500J0D01*
G03Y316113I1125J-995D01*
G02X401512Y315782I-375J-331D01*
G01Y268434D01*
G02X401387Y268103I-500J0D01*
G03Y266113I1125J-995D01*
G02X401512Y265782I-375J-331D01*
G01Y218434D01*
G02X401387Y218103I-500J0D01*
G03Y216113I1125J-995D01*
G02X401512Y215782I-375J-331D01*
G01Y168434D01*
G02X401387Y168103I-500J0D01*
G03Y166113I1125J-995D01*
G02X401512Y165782I-375J-331D01*
G01Y118434D01*
G02X401387Y118103I-500J0D01*
G03Y116113I1125J-995D01*
G02X401512Y115782I-375J-331D01*
G01Y68434D01*
G02X401387Y68103I-500J0D01*
G03Y66113I1125J-995D01*
G02X401512Y65782I-375J-331D01*
G01Y18434D01*
G02X401387Y18103I-500J0D01*
G03Y16113I1125J-995D01*
G02X401512Y15782I-375J-331D01*
G01Y7874D01*
G02X397638Y4000I-3874J0D01*
G01X376547D01*
X376220Y4124D01*
X376159Y4173D01*
G03X374279I-940J-1171D01*
G01X374218Y4124D01*
X373891Y4000D01*
X326547D01*
X326220Y4124D01*
X326159Y4173D01*
G03X324279I-940J-1171D01*
G01X324218Y4124D01*
X323891Y4000D01*
X276547D01*
X276220Y4124D01*
X276159Y4173D01*
G03X274279I-940J-1171D01*
G01X274218Y4124D01*
X273891Y4000D01*
X226547D01*
X226220Y4124D01*
X226159Y4173D01*
G03X224279I-940J-1171D01*
G01X224218Y4124D01*
X223891Y4000D01*
X176547D01*
X176220Y4124D01*
X176159Y4173D01*
G03X174279I-940J-1171D01*
G01X174218Y4124D01*
X173891Y4000D01*
X126547D01*
X126220Y4124D01*
X126159Y4173D01*
G03X124279I-940J-1171D01*
G01X124218Y4124D01*
X123891Y4000D01*
X104331D01*
G37*
%LPD*%
G75*
G36*
G01X292850Y1881102D02*
Y1885039D01*
G02X321322I14236J0D01*
G01Y1881102D01*
G02X292850I-14236J0D01*
G37*
G36*
G01X17976Y989245D02*
Y990190D01*
G02X22970Y990185I2491J-5857D01*
G01Y989240D01*
G03X23209Y988813I500J0D01*
G02X23856Y988346I-2741J-4480D01*
G01X25407D01*
G02X14103Y984333I-4940J-4013D01*
G02X15503Y988316I6365J0D01*
G01X17045D01*
G02X17736Y988818I3422J-3984D01*
G03X17976Y989245I-260J427D01*
G37*
G36*
G01X17980Y1347510D02*
Y1348455D01*
G02X22974Y1348450I2491J-5857D01*
G01Y1347505D01*
G03X23213Y1347078I500J0D01*
G02X23859Y1346612I-2741J-4480D01*
G01X25411D01*
G02X14107Y1342598I-4939J-4014D01*
G02X15507Y1346580I6365J-1D01*
G01X17048D01*
G02X17740Y1347083I3424J-3982D01*
G03X17980Y1347510I-260J427D01*
G37*
G54D42*
X65354Y1514960D03*
Y814960D03*
G54D51*
X307086Y308267D03*
G54D50*
X163385Y27205D03*
Y202205D03*
Y377205D03*
X163386Y552205D03*
Y727205D03*
X163385Y902205D03*
Y1077205D03*
Y1252205D03*
Y1427205D03*
Y1602205D03*
Y1777205D03*
Y1952205D03*
G54D47*
X57735Y2026661D03*
Y1922291D03*
Y390834D03*
Y268811D03*
Y181976D03*
Y59953D03*
G54D49*
X20472Y1054606D03*
G54D45*
X373385Y1957520D03*
Y1782520D03*
Y1607520D03*
Y1432520D03*
Y1257520D03*
Y1082520D03*
Y907520D03*
X373386Y732520D03*
Y557520D03*
X373385Y382520D03*
Y207520D03*
Y32520D03*
G54D40*
X307087Y2043503D03*
Y1693503D03*
Y1343503D03*
Y827164D03*
X307088Y477164D03*
X307086Y127164D03*
G54D48*
X58995Y1587992D03*
Y543701D03*
X13995Y1587992D03*
Y543701D03*
G54D46*
X359842Y2003780D03*
Y1828779D03*
Y1653780D03*
Y1478780D03*
Y1303780D03*
Y1128779D03*
Y953780D03*
Y778780D03*
Y603779D03*
Y428779D03*
Y253780D03*
Y78780D03*
G54D43*
X65354Y1164960D03*
G54D44*
Y114960D03*
G54D41*
Y1864960D03*
Y464960D03*
G54D11*
X25219Y18752D03*
X3001Y52034D03*
Y100034D03*
Y150034D03*
Y200034D03*
Y250034D03*
Y300034D03*
Y350034D03*
Y400034D03*
Y450034D03*
Y500034D03*
Y550034D03*
X11677Y578766D03*
X3001Y600034D03*
Y650034D03*
Y700034D03*
Y750034D03*
Y800034D03*
Y850034D03*
Y900034D03*
Y950034D03*
Y1000034D03*
Y1050034D03*
Y1100034D03*
Y1150034D03*
Y1200034D03*
Y1250034D03*
Y1300034D03*
Y1350034D03*
Y1400034D03*
Y1450034D03*
Y1500034D03*
Y1550034D03*
X16484Y1552159D03*
X11085Y1552589D03*
X3006Y1594602D03*
X3012Y1610165D03*
X3001Y1650034D03*
Y1700034D03*
Y1750034D03*
Y1800034D03*
Y1850034D03*
Y1900034D03*
Y1950034D03*
Y2000034D03*
Y2050034D03*
X48433Y866179D03*
X48467Y869278D03*
X49441Y1238962D03*
X46980Y1335843D03*
Y1325843D03*
Y1315843D03*
Y1320843D03*
Y1330843D03*
Y1345843D03*
Y1340843D03*
X26833Y2067866D03*
X58750Y579653D03*
X63820Y579654D03*
X61888Y666012D03*
X57124Y675327D03*
X54483Y679810D03*
X59236Y670758D03*
X70865Y854278D03*
Y872278D03*
Y866278D03*
Y860278D03*
Y897750D03*
Y890116D03*
X60815Y1019026D03*
X63577Y1019115D03*
X57458Y1253378D03*
X54543Y1296513D03*
X63061Y1296312D03*
X67568Y1296654D03*
X61866Y1309190D03*
X67568Y1307829D03*
X54543Y1308995D03*
X61866Y1342104D03*
X54108Y1559138D03*
X75219Y18752D03*
X97417Y32853D03*
Y37438D03*
X97536Y376580D03*
X97457Y371909D03*
X97985Y391220D03*
X97643Y396024D03*
X93223Y417736D03*
X94347Y421562D03*
X98591Y720745D03*
X98564Y715937D03*
X97443Y739962D03*
X97534Y735248D03*
X98124Y745139D03*
X95775Y751469D03*
X92216Y899865D03*
X90708Y878615D03*
X92633Y907404D03*
X92989Y927334D03*
X98139Y990959D03*
X76446Y1014871D03*
X79499D03*
X96904Y1067515D03*
X82763Y1060051D03*
X96948Y1092036D03*
X96949Y1087095D03*
X96774Y1072226D03*
X96684Y1081791D03*
X75475Y1315303D03*
X96510Y1395382D03*
X97403Y1424340D03*
X97825Y1419492D03*
X96993Y1443743D03*
X96996Y1438980D03*
X97465Y1447919D03*
X95236Y1453321D03*
X76833Y2067866D03*
X106335Y22580D03*
X106958Y26285D03*
X108082Y38899D03*
X102646Y49461D03*
X101430Y41803D03*
X107405Y49898D03*
X107037Y34687D03*
X104350Y62293D03*
X107263Y72244D03*
X109054Y58250D03*
X104116Y82557D03*
X107213Y85169D03*
X106836Y376461D03*
X106709Y391219D03*
X105451Y406795D03*
X114498Y396207D03*
X101990Y426104D03*
X109475Y434743D03*
X111017Y419566D03*
X107025Y725368D03*
X105087Y754126D03*
X106935Y745139D03*
X107173Y735219D03*
X101244Y774100D03*
X112836Y769122D03*
X113697Y794293D03*
X105395Y972040D03*
X102611Y972220D03*
X100687Y999391D03*
X107351Y1093484D03*
X107235Y1081791D03*
X107215Y1072208D03*
X98652Y1096403D03*
X108779Y1105760D03*
X105152Y1118381D03*
X112503Y1115860D03*
X105684Y1125919D03*
X108468Y1129286D03*
X100719Y1312810D03*
Y1306810D03*
Y1330810D03*
Y1336810D03*
Y1324810D03*
Y1318810D03*
Y1346065D03*
X101626Y1397635D03*
X106962Y1434041D03*
X106921Y1419492D03*
X106763Y1444599D03*
X107006Y1452651D03*
X105455Y1472894D03*
X108574Y1463389D03*
X113518Y1489571D03*
X99103Y1765722D03*
X99068Y1760827D03*
X107355Y1770437D03*
X99047Y1785571D03*
X98873Y1780542D03*
X99294Y1789947D03*
X107391Y1794460D03*
X107220Y1791589D03*
X107373Y1780544D03*
X105669Y1815227D03*
X108819Y1812118D03*
X106819Y1802230D03*
X108819Y1824470D03*
X109991Y2083607D03*
X125219Y3002D03*
X144878Y1738861D03*
X162384Y56744D03*
X157558Y51426D03*
X161742Y72497D03*
X162586Y68130D03*
X159417Y91281D03*
X158901Y85017D03*
X161377Y407575D03*
X156865Y401207D03*
X161257Y420869D03*
X159019Y439268D03*
X158807Y432969D03*
X156610Y751063D03*
X161826Y756757D03*
X161131Y774878D03*
X161644Y764231D03*
X158956Y780982D03*
X159053Y787280D03*
X164539Y1116135D03*
X162140Y1106853D03*
X156854Y1101031D03*
X159382Y1136151D03*
X158456Y1129045D03*
X158618Y1399448D03*
X164037Y1400226D03*
X170351Y1401324D03*
X159192Y1451105D03*
X163099Y1457084D03*
X162524Y1462651D03*
X162242Y1471380D03*
X159216Y1477124D03*
X159526Y1483434D03*
X150309Y1737009D03*
X168151Y1739208D03*
X156183Y1735240D03*
X165782Y1732903D03*
X163257Y1737619D03*
X163250Y1815631D03*
X162140Y1807740D03*
X156452Y1800821D03*
X159822Y1831380D03*
X159075Y1825087D03*
X159991Y2083607D03*
X175219Y3002D03*
X184284Y948331D03*
X175989Y944537D03*
X176011Y936829D03*
X184196Y967371D03*
X175359Y963486D03*
X175561Y955964D03*
X175135Y972490D03*
X184632Y983423D03*
X175022Y980281D03*
X175742Y989958D03*
X175449Y997660D03*
X184353Y1001556D03*
X184118Y1019280D03*
X188385Y1020810D03*
X175698Y1008730D03*
X175473Y1016296D03*
X175448Y1031766D03*
X175897Y1023997D03*
X176083Y1402321D03*
X173394Y1736051D03*
X209991Y2083607D03*
X225219Y3002D03*
X267627Y115559D03*
X256947Y128276D03*
X257125Y115559D03*
X265722Y463102D03*
X265737Y473680D03*
X255837Y823626D03*
X255687Y812192D03*
X259991Y2083607D03*
X275219Y3002D03*
X287420Y162540D03*
X283086Y162675D03*
X271547Y245353D03*
X276617Y241400D03*
X281193Y241624D03*
X285513Y337688D03*
X281074D03*
X289895D03*
X286665Y417844D03*
X291002D03*
X281569Y421169D03*
X274991Y463099D03*
X282776Y512341D03*
X278405D03*
X273938D03*
X269516D03*
X285348Y595540D03*
X290984Y592215D03*
X274514Y687192D03*
X270109D03*
X283340D03*
X278955D03*
X273114Y770968D03*
X278184Y767643D03*
X282737D03*
X270070Y812192D03*
X276686Y862488D03*
X272181Y862354D03*
X285788Y862237D03*
X281305D03*
X275966Y944767D03*
X281194Y941442D03*
X285874D03*
X285666Y1031162D03*
X281124D03*
X290107D03*
X282958Y1119471D03*
X288188Y1116146D03*
X289082Y1206777D03*
X284194D03*
X279559D03*
X283808Y1293959D03*
X289210Y1290634D03*
X284240Y1389544D03*
X279518Y1389543D03*
X275052Y1389715D03*
X270579Y1389626D03*
X270234Y1467760D03*
X275521Y1464435D03*
X279990D03*
X289675Y1558211D03*
X285054D03*
X284086Y1644883D03*
X289421Y1641558D03*
X274704Y1738196D03*
X279703Y1738398D03*
X284583Y1738465D03*
X289499Y1738735D03*
X281066Y1819569D03*
X291550Y1814846D03*
X286623Y1814400D03*
X280240Y1858668D03*
X279976Y1864565D03*
X287121Y1913327D03*
X282717D03*
X278262D03*
X273817D03*
X299687Y63778D03*
X304151D03*
X308651D03*
X313089D03*
X294483Y67732D03*
X296523Y162585D03*
X291943Y162630D03*
X308057Y248863D03*
X306267Y241010D03*
X314914Y238162D03*
X314940Y252083D03*
X305867Y258589D03*
X294506Y337688D03*
X295509Y592215D03*
X294617Y1031162D03*
X309678Y1053262D03*
X292698Y1116146D03*
X312527Y1162266D03*
X312698Y1172804D03*
X293807Y1206777D03*
X294133Y1290634D03*
X314183Y1403423D03*
X313894Y1513883D03*
X302267Y1524401D03*
X301734Y1513883D03*
X312077Y1575871D03*
X298870Y1558211D03*
X294392D03*
X294090Y1641558D03*
X311539Y1753499D03*
X293606Y1858668D03*
X314562Y1994087D03*
X309991Y2083607D03*
X325219Y3002D03*
X331403Y51409D03*
X333889Y56021D03*
X338227Y61559D03*
X322005Y63778D03*
X317567D03*
X320372Y225979D03*
X318088Y231820D03*
X321899Y238137D03*
X329930Y245684D03*
X331046Y232021D03*
X320961Y250105D03*
X324709Y231580D03*
X335522Y404033D03*
X323313Y418313D03*
X326196Y413982D03*
X328950Y409216D03*
X320980Y423225D03*
X336617Y577978D03*
X319305Y582111D03*
X329636Y584715D03*
X317724Y588250D03*
X337387Y586230D03*
X320380Y576491D03*
X331867Y589810D03*
X333750Y595326D03*
X323751Y589155D03*
X319852Y593330D03*
X321742Y599041D03*
X331568Y752967D03*
X339012Y752859D03*
X329336Y762693D03*
X334010Y758588D03*
X327524Y758020D03*
X339615Y926357D03*
X329938Y948756D03*
X332527Y943746D03*
X324098Y946104D03*
X318557Y941178D03*
X323868Y929978D03*
X326646Y939788D03*
X333300Y928464D03*
X336160Y937262D03*
X328583Y933262D03*
X321425Y951577D03*
X324246Y1051786D03*
X335677Y1048904D03*
X317592Y1053050D03*
X331920Y1116088D03*
X337509Y1109598D03*
X328989Y1121090D03*
X326558Y1126368D03*
X325796Y1162266D03*
X327452Y1279447D03*
X321978Y1282086D03*
X338047Y1282599D03*
X333242Y1276809D03*
X329619Y1284016D03*
X327932Y1289221D03*
X319404Y1401346D03*
X325636Y1399114D03*
X334646Y1400804D03*
X323720Y1570924D03*
X329399Y1571939D03*
X317243Y1574832D03*
X333474Y1566686D03*
X335963Y1573797D03*
X329887Y1752081D03*
X321283Y1753466D03*
X335730Y1753270D03*
X338309Y1927623D03*
X332399Y1926787D03*
X324803Y1990272D03*
X320045Y1990215D03*
X359931Y52189D03*
X348289Y50863D03*
X345089Y56190D03*
X340373Y51579D03*
X342097Y401684D03*
X363825Y401768D03*
X342900Y580126D03*
X362577Y752783D03*
X344109Y751809D03*
X343656Y933725D03*
X345578Y1047844D03*
X344099Y1106798D03*
X349855Y1104302D03*
X344130Y1401670D03*
X350690Y1403243D03*
X348710Y1570187D03*
X361011Y1568890D03*
X343402Y1572080D03*
X348245Y1575241D03*
X355364Y1570990D03*
X345537Y1916558D03*
X344402Y1911123D03*
X363361Y1918313D03*
X358318Y1920680D03*
X363411Y1923459D03*
X340336Y1922409D03*
X347676Y1922165D03*
X359991Y2083607D03*
X375219Y3002D03*
X372204Y56126D03*
X365720Y52336D03*
X379257Y52158D03*
X379572Y58441D03*
X387524Y76847D03*
X374442Y406857D03*
X380619Y410112D03*
X380878Y403999D03*
X374542Y401282D03*
X368907Y404308D03*
X376654Y754748D03*
X382892Y767710D03*
X386790Y774338D03*
X380186Y761742D03*
X379335Y1189778D03*
X383276Y1184136D03*
X386816Y1179841D03*
X376472Y1194999D03*
X373674Y1199967D03*
X371523Y1204725D03*
X367829Y1566108D03*
X374775Y1919243D03*
X379403Y1917261D03*
X369748Y1921795D03*
X402512Y17108D03*
Y67108D03*
Y117108D03*
Y167108D03*
Y217108D03*
Y267108D03*
Y317108D03*
Y367108D03*
Y417108D03*
Y467108D03*
Y517108D03*
Y567108D03*
Y617108D03*
Y667108D03*
Y717108D03*
Y767108D03*
X391278Y765894D03*
X402512Y817108D03*
Y867108D03*
Y917108D03*
Y967108D03*
Y1017108D03*
Y1067108D03*
Y1117108D03*
Y1167108D03*
Y1217108D03*
Y1267108D03*
Y1317108D03*
Y1367108D03*
Y1417108D03*
Y1467108D03*
Y1517108D03*
Y1567108D03*
Y1617108D03*
Y1667108D03*
Y1717108D03*
Y1767108D03*
Y1817108D03*
Y1867108D03*
Y1917108D03*
Y1967108D03*
Y2017108D03*
Y2067108D03*
G54D28*
X166500Y126110D03*
Y118626D03*
Y111407D03*
X166329Y140623D03*
X166500Y132705D03*
X166329Y148066D03*
Y156102D03*
Y163621D03*
X156430Y461714D03*
Y483012D03*
X156259Y490930D03*
X156430Y468933D03*
Y476417D03*
X156259Y513928D03*
Y498373D03*
Y506409D03*
X155444Y822725D03*
X162872D03*
Y830209D03*
X155444D03*
X171524Y844722D03*
Y852165D03*
X162872Y836804D03*
X155444D03*
X162701Y844722D03*
X155273D03*
X162701Y852165D03*
X155273D03*
X171524Y860201D03*
Y867720D03*
X162701Y860201D03*
X155273D03*
X162701Y867720D03*
X155273D03*
X169375Y1176256D03*
Y1190335D03*
Y1183740D03*
X153124Y1176256D03*
X160552D03*
Y1183740D03*
Y1190335D03*
X153124D03*
Y1183740D03*
X160552Y1169037D03*
X153124D03*
X169204Y1198253D03*
X160381D03*
X152953D03*
X154109Y1499221D03*
X161537D03*
Y1506440D03*
X170360D03*
X154109D03*
X153938Y1528437D03*
X154109Y1513924D03*
Y1520519D03*
X170360Y1513924D03*
Y1520519D03*
X161537D03*
Y1513924D03*
X161366Y1528437D03*
X170189D03*
X153938Y1535880D03*
Y1543916D03*
Y1551435D03*
X170189Y1535880D03*
Y1543916D03*
X161366Y1535880D03*
Y1543916D03*
Y1551435D03*
X170189D03*
X152091Y1866003D03*
X159519D03*
X152091Y1880706D03*
Y1887301D03*
X168342Y1880706D03*
Y1887301D03*
X159519D03*
Y1880706D03*
Y1873222D03*
X168342D03*
X152091D03*
X151920Y1902662D03*
Y1910698D03*
X168171Y1902662D03*
Y1910698D03*
X159348Y1902662D03*
Y1910698D03*
X151920Y1895219D03*
X159348D03*
X168171D03*
X151920Y1918217D03*
X159348D03*
X168171D03*
X173928Y126110D03*
Y118626D03*
Y111407D03*
X173757Y140623D03*
X173928Y132705D03*
X173757Y148066D03*
Y156102D03*
Y163621D03*
X175033Y261594D03*
Y268813D03*
Y282892D03*
X174862Y290810D03*
Y298253D03*
X175033Y276297D03*
X174862Y313808D03*
Y306289D03*
X179191Y822725D03*
Y830209D03*
X171695Y822725D03*
Y830209D03*
X179191Y836804D03*
X171695D03*
X179020Y844722D03*
Y852165D03*
Y860201D03*
Y867720D03*
X176871Y1176256D03*
Y1190335D03*
Y1183740D03*
X176700Y1198253D03*
X177856Y1506440D03*
Y1513924D03*
Y1520519D03*
X177685Y1528437D03*
Y1535880D03*
Y1543916D03*
Y1551435D03*
X175838Y1880706D03*
Y1887301D03*
Y1873222D03*
X175667Y1902662D03*
Y1910698D03*
Y1895219D03*
Y1918217D03*
X240955Y56999D03*
Y64483D03*
X240784Y78996D03*
X240955Y71078D03*
X240784Y94475D03*
Y101994D03*
Y86439D03*
X236537Y244995D03*
X227714Y237776D03*
Y244995D03*
X244033D03*
X236537Y259074D03*
X236366Y266992D03*
Y274435D03*
X227714Y259074D03*
X227543Y266992D03*
Y274435D03*
X244033Y259074D03*
X243862Y266992D03*
Y274435D03*
X236537Y252479D03*
X227714D03*
X244033D03*
X236366Y289990D03*
X227543D03*
X243862D03*
X236366Y282471D03*
X227543D03*
X243862D03*
X232548Y461083D03*
X241371Y482381D03*
X241200Y490299D03*
X232548Y482381D03*
X232377Y490299D03*
X241371Y468302D03*
Y475786D03*
X232548Y468302D03*
Y475786D03*
X241200Y513297D03*
X232377D03*
X241200Y497742D03*
X232377D03*
X241200Y505778D03*
X232377D03*
X230963Y608108D03*
X238391D03*
X230963Y601513D03*
X238391D03*
Y594029D03*
X230963D03*
X230792Y631505D03*
X238220D03*
X230792Y623469D03*
X238220D03*
X230792Y616026D03*
X238220D03*
X230792Y639024D03*
X238220D03*
X231339Y959673D03*
X238767D03*
Y967157D03*
Y973752D03*
X231339D03*
Y967157D03*
X238767Y952454D03*
X231339D03*
X238596Y981670D03*
X231168D03*
X238596Y997149D03*
Y989113D03*
X231168Y997149D03*
Y989113D03*
X238596Y1004668D03*
X231168D03*
X238659Y1215296D03*
X231231D03*
X238659Y1207777D03*
Y1199741D03*
X231231Y1207777D03*
Y1199741D03*
X225131Y1663167D03*
X241382Y1670386D03*
X232559Y1663167D03*
Y1670386D03*
X225131D03*
X241211Y1699826D03*
X241382Y1677870D03*
X241211Y1692383D03*
X241382Y1684465D03*
X232559D03*
Y1677870D03*
X232388Y1692383D03*
Y1699826D03*
X225131Y1684465D03*
Y1677870D03*
X224960Y1692383D03*
Y1699826D03*
X241211Y1715381D03*
Y1707862D03*
X232388D03*
Y1715381D03*
X224960Y1707862D03*
Y1715381D03*
X248451Y56999D03*
Y64483D03*
X248280Y78996D03*
X248451Y71078D03*
X248280Y94475D03*
Y101994D03*
Y86439D03*
X248867Y482381D03*
X248696Y490299D03*
X248867Y468302D03*
Y475786D03*
X248696Y513297D03*
Y497742D03*
Y505778D03*
X254710Y608108D03*
Y601513D03*
Y594029D03*
X247214Y608108D03*
Y601513D03*
Y594029D03*
X254539Y631505D03*
Y623469D03*
Y616026D03*
X247043Y631505D03*
Y623469D03*
Y616026D03*
X267433Y624321D03*
X254539Y639024D03*
X247043D03*
X255086Y959673D03*
Y973752D03*
Y967157D03*
X247590Y959673D03*
Y973752D03*
Y967157D03*
X254915Y981670D03*
Y997149D03*
Y989113D03*
X247419Y981670D03*
Y997149D03*
Y989113D03*
X254915Y1004668D03*
X247419D03*
X254978Y1215296D03*
X247482D03*
X254978Y1207777D03*
Y1199741D03*
X247482Y1207777D03*
Y1199741D03*
X248878Y1670386D03*
X248707Y1699826D03*
X248878Y1677870D03*
Y1684465D03*
X248707Y1692383D03*
Y1707862D03*
Y1715381D03*
X279044Y624627D03*
X354391Y1329686D03*
Y1350706D03*
Y1360043D03*
Y1340201D03*
Y1376210D03*
Y1367771D03*
X366169Y1329686D03*
Y1350706D03*
Y1360043D03*
Y1340201D03*
Y1376210D03*
Y1367771D03*
G54D31*
X173385Y32520D03*
Y21890D03*
X183385Y32520D03*
Y21890D03*
X193385Y32520D03*
Y21890D03*
X173385Y196890D03*
X183385D03*
X193385D03*
X173385Y207520D03*
X183385D03*
X193385D03*
X173385Y371890D03*
X183385D03*
X193385D03*
X173385Y382520D03*
X183385D03*
X193385D03*
X173386Y557520D03*
Y546890D03*
X183386Y557520D03*
Y546890D03*
X193386Y557520D03*
Y546890D03*
X173386Y732520D03*
Y721890D03*
X183386Y732520D03*
Y721890D03*
X193386Y732520D03*
Y721890D03*
X173385Y896890D03*
X183385D03*
X193385D03*
X173385Y907520D03*
X183385D03*
X193385D03*
X173385Y1071890D03*
X183385D03*
X193385D03*
X173385Y1082520D03*
X183385D03*
X193385D03*
X173385Y1257520D03*
Y1246890D03*
X183385Y1257520D03*
Y1246890D03*
X193385Y1257520D03*
Y1246890D03*
X173385Y1432520D03*
Y1421890D03*
X183385Y1432520D03*
Y1421890D03*
X193385Y1432520D03*
Y1421890D03*
X173385Y1596890D03*
X183385D03*
X193385D03*
X173385Y1607520D03*
X183385D03*
X193385D03*
X173385Y1771890D03*
X183385D03*
X193385D03*
X173385Y1782520D03*
X183385D03*
X193385D03*
X173385Y1957520D03*
Y1946890D03*
X183385Y1957520D03*
Y1946890D03*
X193385Y1957520D03*
Y1946890D03*
X203385Y32520D03*
Y21890D03*
X213385Y32520D03*
Y21890D03*
X203385Y196890D03*
X213385D03*
X203385Y207520D03*
X213385D03*
X203385Y371890D03*
X213385D03*
X203385Y382520D03*
X213385D03*
X203386Y557520D03*
Y546890D03*
X213386Y557520D03*
Y546890D03*
X203386Y732520D03*
Y721890D03*
X213386Y732520D03*
Y721890D03*
X203385Y896890D03*
X213385D03*
X203385Y907520D03*
X213385D03*
X203385Y1071890D03*
X213385D03*
X203385Y1082520D03*
X213385D03*
X203385Y1257520D03*
Y1246890D03*
X213385Y1257520D03*
Y1246890D03*
X203385Y1432520D03*
Y1421890D03*
X213385Y1432520D03*
Y1421890D03*
X203385Y1596890D03*
X213385D03*
X203385Y1607520D03*
X213385D03*
X203385Y1771890D03*
X213385D03*
X203385Y1782520D03*
X213385D03*
X203385Y1957520D03*
Y1946890D03*
X213385Y1957520D03*
Y1946890D03*
X223385Y32520D03*
Y21890D03*
X233385Y32520D03*
Y21890D03*
X243385Y32520D03*
Y21890D03*
X223385Y196890D03*
X233385D03*
X243385D03*
X223385Y207520D03*
X233385D03*
X243385D03*
X223385Y371890D03*
X233385D03*
X243385D03*
X223385Y382520D03*
X233385D03*
X243385D03*
X223386Y557520D03*
Y546890D03*
X233386Y557520D03*
Y546890D03*
X243386Y557520D03*
Y546890D03*
X223386Y732520D03*
Y721890D03*
X233386Y732520D03*
Y721890D03*
X243386Y732520D03*
Y721890D03*
X223385Y896890D03*
X233385D03*
X243385D03*
X223385Y907520D03*
X233385D03*
X243385D03*
X223385Y1071890D03*
X233385D03*
X243385D03*
X223385Y1082520D03*
X233385D03*
X243385D03*
X223385Y1257520D03*
Y1246890D03*
X233385Y1257520D03*
Y1246890D03*
X243385Y1257520D03*
Y1246890D03*
X223385Y1432520D03*
Y1421890D03*
X233385Y1432520D03*
Y1421890D03*
X243385Y1432520D03*
Y1421890D03*
X223385Y1596890D03*
X233385D03*
X243385D03*
X223385Y1607520D03*
X233385D03*
X243385D03*
X223385Y1771890D03*
X233385D03*
X243385D03*
X223385Y1782520D03*
X233385D03*
X243385D03*
X223385Y1957520D03*
Y1946890D03*
X233385Y1957520D03*
Y1946890D03*
X243385Y1957520D03*
Y1946890D03*
X337165Y24705D03*
Y34705D03*
Y199705D03*
Y209705D03*
Y374705D03*
Y384705D03*
X337166Y549705D03*
Y559705D03*
Y724705D03*
Y734705D03*
X337165Y899705D03*
Y909705D03*
Y1074705D03*
Y1084705D03*
Y1249705D03*
Y1259705D03*
Y1424705D03*
Y1434705D03*
Y1599705D03*
Y1609705D03*
Y1774705D03*
Y1784705D03*
Y1949705D03*
Y1959705D03*
X342165Y19705D03*
Y29705D03*
X347165Y24705D03*
X352165Y19705D03*
Y29705D03*
X357165Y24705D03*
X362165Y19705D03*
Y29705D03*
X347165Y34705D03*
X357165D03*
X342165Y194705D03*
X347165Y199705D03*
X352165Y194705D03*
X357165Y199705D03*
X362165Y194705D03*
X342165Y204705D03*
X347165Y209705D03*
X352165Y204705D03*
X357165Y209705D03*
X362165Y204705D03*
X342165Y369705D03*
X352165D03*
X362165D03*
X342165Y379705D03*
X347165Y374705D03*
Y384705D03*
X352165Y379705D03*
X357165Y374705D03*
Y384705D03*
X362165Y379705D03*
X342166Y544705D03*
Y554705D03*
X347166Y549705D03*
Y559705D03*
X352166Y544705D03*
Y554705D03*
X357166Y549705D03*
Y559705D03*
X362166Y544705D03*
Y554705D03*
X342166Y719705D03*
Y729705D03*
X347166Y724705D03*
X352166Y719705D03*
Y729705D03*
X357166Y724705D03*
X362166Y719705D03*
Y729705D03*
X347166Y734705D03*
X357166D03*
X342165Y894705D03*
X347165Y899705D03*
X352165Y894705D03*
X357165Y899705D03*
X362165Y894705D03*
X342165Y904705D03*
X347165Y909705D03*
X352165Y904705D03*
X357165Y909705D03*
X362165Y904705D03*
X342165Y1069705D03*
X352165D03*
X362165D03*
X342165Y1079705D03*
X347165Y1074705D03*
Y1084705D03*
X352165Y1079705D03*
X357165Y1074705D03*
Y1084705D03*
X362165Y1079705D03*
X342165Y1244705D03*
Y1254705D03*
X347165Y1249705D03*
Y1259705D03*
X352165Y1244705D03*
Y1254705D03*
X357165Y1249705D03*
Y1259705D03*
X362165Y1244705D03*
Y1254705D03*
X342165Y1419705D03*
Y1429705D03*
X347165Y1424705D03*
Y1434705D03*
X352165Y1419705D03*
Y1429705D03*
X357165Y1424705D03*
Y1434705D03*
X362165Y1419705D03*
Y1429705D03*
X342165Y1594705D03*
X347165Y1599705D03*
X352165Y1594705D03*
X357165Y1599705D03*
X362165Y1594705D03*
X342165Y1604705D03*
X347165Y1609705D03*
X352165Y1604705D03*
X357165Y1609705D03*
X362165Y1604705D03*
X342165Y1769705D03*
X352165D03*
X362165D03*
X342165Y1779705D03*
X347165Y1774705D03*
Y1784705D03*
X352165Y1779705D03*
X357165Y1774705D03*
Y1784705D03*
X362165Y1779705D03*
X342165Y1944705D03*
Y1954705D03*
X347165Y1949705D03*
Y1959705D03*
X352165Y1944705D03*
Y1954705D03*
X357165Y1949705D03*
Y1959705D03*
X362165Y1944705D03*
Y1954705D03*
G54D16*
X17480Y599901D03*
X9606D03*
X17480Y627264D03*
X9606D03*
X17480Y1471949D03*
X9606D03*
X17480Y1499311D03*
X9606D03*
G54D22*
X65354Y101180D03*
X55511Y105117D03*
X51574Y114960D03*
X55511Y124803D03*
X65354Y128740D03*
Y451180D03*
X55511Y455117D03*
X51574Y464960D03*
X55511Y474803D03*
X65354Y478740D03*
Y801180D03*
X55511Y805117D03*
X51574Y814960D03*
X55511Y824803D03*
X65354Y828740D03*
Y1151180D03*
X55511Y1155117D03*
X51574Y1164960D03*
X55511Y1174803D03*
X65354Y1178740D03*
Y1501180D03*
X55511Y1505117D03*
X51574Y1514960D03*
X55511Y1524803D03*
X65354Y1528740D03*
Y1851180D03*
X55511Y1855117D03*
X51574Y1864960D03*
X55511Y1874803D03*
X65354Y1878740D03*
X75197Y105117D03*
Y124803D03*
X79134Y114960D03*
Y464960D03*
X75197Y455117D03*
Y474803D03*
Y805117D03*
Y824803D03*
X79134Y814960D03*
Y1164960D03*
X75197Y1155117D03*
Y1174803D03*
Y1505117D03*
Y1524803D03*
X79134Y1514960D03*
Y1864960D03*
X75197Y1855117D03*
Y1874803D03*
X307086Y113385D03*
X297243Y117322D03*
X293306Y127165D03*
X297243Y137008D03*
X307086Y140945D03*
Y463385D03*
X297243Y467322D03*
X293306Y477165D03*
X297243Y487008D03*
X307086Y490945D03*
Y813385D03*
X297243Y817322D03*
X293306Y827165D03*
X297243Y837008D03*
X307086Y840945D03*
Y1329724D03*
X297243Y1333661D03*
X293306Y1343504D03*
X297243Y1353347D03*
X307086Y1357284D03*
Y1679724D03*
X297243Y1683661D03*
X293306Y1693504D03*
X297243Y1703347D03*
X307086Y1707284D03*
X307087Y2029723D03*
X297244Y2033660D03*
X293307Y2043503D03*
X297244Y2053346D03*
X307087Y2057283D03*
X320866Y127165D03*
X316929Y117322D03*
Y137008D03*
Y467322D03*
Y487008D03*
X320866Y477165D03*
Y827165D03*
X316929Y817322D03*
Y837008D03*
Y1333661D03*
Y1353347D03*
X320866Y1343504D03*
Y1693504D03*
X316929Y1683661D03*
Y1703347D03*
X316930Y2033660D03*
Y2053346D03*
X320867Y2043503D03*
G54D25*
X119920Y18071D03*
Y28071D03*
Y38071D03*
Y48071D03*
Y58071D03*
Y68071D03*
Y78071D03*
Y88071D03*
Y98071D03*
Y108071D03*
Y118071D03*
Y128071D03*
Y138071D03*
Y148071D03*
Y158071D03*
Y168071D03*
Y178071D03*
Y188071D03*
Y198071D03*
Y208071D03*
Y366102D03*
Y376102D03*
Y386102D03*
Y396102D03*
Y406102D03*
Y416102D03*
Y426102D03*
Y436102D03*
Y446102D03*
Y456102D03*
Y466102D03*
Y476102D03*
Y486102D03*
Y496102D03*
Y506102D03*
Y516102D03*
Y526102D03*
Y536102D03*
Y546102D03*
Y556102D03*
Y714134D03*
Y724134D03*
Y734134D03*
Y744134D03*
Y754134D03*
Y764134D03*
Y774134D03*
Y784134D03*
Y794134D03*
Y804134D03*
Y814134D03*
Y824134D03*
Y834134D03*
Y844134D03*
Y854134D03*
Y864134D03*
Y874134D03*
Y884134D03*
Y894134D03*
Y904134D03*
Y1062165D03*
Y1072165D03*
Y1082165D03*
Y1092165D03*
Y1102165D03*
Y1112165D03*
Y1122165D03*
Y1132165D03*
Y1142165D03*
Y1152165D03*
Y1162165D03*
Y1172165D03*
Y1182165D03*
Y1192165D03*
Y1202165D03*
Y1212165D03*
Y1222165D03*
Y1232165D03*
Y1242165D03*
Y1252165D03*
Y1410197D03*
Y1420197D03*
Y1430197D03*
Y1440197D03*
Y1450197D03*
Y1460197D03*
Y1470197D03*
Y1480197D03*
Y1490197D03*
Y1500197D03*
Y1510197D03*
Y1520197D03*
Y1530197D03*
Y1540197D03*
Y1550197D03*
Y1560197D03*
Y1570197D03*
Y1580197D03*
Y1590197D03*
Y1600197D03*
Y1758228D03*
Y1768228D03*
Y1778228D03*
Y1788228D03*
Y1798228D03*
Y1808228D03*
Y1818228D03*
Y1828228D03*
Y1838228D03*
Y1848228D03*
Y1858228D03*
Y1868228D03*
Y1878228D03*
Y1888228D03*
Y1898228D03*
Y1908228D03*
Y1918228D03*
Y1928228D03*
Y1938228D03*
Y1948228D03*
X139920Y28071D03*
Y18071D03*
Y58071D03*
Y48071D03*
Y38071D03*
Y78071D03*
Y68071D03*
Y98071D03*
Y88071D03*
Y128071D03*
Y118071D03*
Y108071D03*
Y148071D03*
Y138071D03*
Y178071D03*
Y168071D03*
Y158071D03*
Y198071D03*
Y188071D03*
Y208071D03*
Y366102D03*
Y396102D03*
Y386102D03*
Y376102D03*
Y416102D03*
Y406102D03*
Y436102D03*
Y426102D03*
Y466102D03*
Y456102D03*
Y446102D03*
Y486102D03*
Y476102D03*
Y516102D03*
Y506102D03*
Y496102D03*
Y536102D03*
Y526102D03*
Y556102D03*
Y546102D03*
Y734134D03*
Y724134D03*
Y714134D03*
Y754134D03*
Y744134D03*
Y774134D03*
Y764134D03*
Y804134D03*
Y794134D03*
Y784134D03*
Y824134D03*
Y814134D03*
Y854134D03*
Y844134D03*
Y834134D03*
Y874134D03*
Y864134D03*
Y904134D03*
Y894134D03*
Y884134D03*
Y1072165D03*
Y1062165D03*
Y1092165D03*
Y1082165D03*
Y1122165D03*
Y1112165D03*
Y1102165D03*
Y1142165D03*
Y1132165D03*
Y1162165D03*
Y1152165D03*
Y1192165D03*
Y1182165D03*
Y1172165D03*
Y1212165D03*
Y1202165D03*
Y1242165D03*
Y1232165D03*
Y1222165D03*
Y1252165D03*
Y1410197D03*
Y1430197D03*
Y1420197D03*
Y1460197D03*
Y1450197D03*
Y1440197D03*
Y1480197D03*
Y1470197D03*
Y1500197D03*
Y1490197D03*
Y1530197D03*
Y1520197D03*
Y1510197D03*
Y1550197D03*
Y1540197D03*
Y1580197D03*
Y1570197D03*
Y1560197D03*
Y1600197D03*
Y1590197D03*
Y1768228D03*
Y1758228D03*
Y1798228D03*
Y1788228D03*
Y1778228D03*
Y1818228D03*
Y1808228D03*
Y1838228D03*
Y1828228D03*
Y1868228D03*
Y1858228D03*
Y1848228D03*
Y1888228D03*
Y1878228D03*
Y1918228D03*
Y1908228D03*
Y1898228D03*
Y1938228D03*
Y1928228D03*
Y1948228D03*
G54D13*
X18995Y508701D03*
X23995Y518701D03*
X21495Y559882D03*
X11692D03*
X21495Y1571811D03*
X11692D03*
X23995Y1622992D03*
X18995Y1612992D03*
X28995Y508701D03*
X38995D03*
X48995D03*
X33995Y518701D03*
X43995D03*
X51495Y559882D03*
Y1571811D03*
X43995Y1622992D03*
X33995D03*
X48995Y1612992D03*
X38995D03*
X28995D03*
X53995Y518701D03*
X61298Y559882D03*
Y1571811D03*
X53995Y1622992D03*
X189762Y73105D03*
X190289Y152050D03*
X190357Y247568D03*
X190817Y331786D03*
X189761Y421732D03*
X190553Y506517D03*
X192888Y598130D03*
X190816Y681645D03*
X191846Y774526D03*
X191606Y856244D03*
X196311Y947202D03*
X195516Y1032544D03*
X191250Y1122856D03*
X191342Y1206233D03*
X191846Y1299104D03*
X190552Y1380966D03*
X189463Y1474162D03*
X191079Y1557277D03*
X192143Y1648177D03*
X191607Y1731351D03*
X191530Y1823227D03*
X190289Y1900420D03*
X192125Y1998730D03*
X191530Y2043388D03*
G54D15*
X5491Y528544D03*
Y1603149D03*
X67499Y528544D03*
Y1603149D03*
G54D17*
X15547Y707364D03*
Y723112D03*
Y730986D03*
X25389Y723112D03*
Y730986D03*
X7673Y719175D03*
Y727049D03*
X15547Y738860D03*
Y746734D03*
Y754608D03*
X25389Y738860D03*
Y746734D03*
Y754608D03*
X7673Y734923D03*
Y742797D03*
Y750671D03*
Y758545D03*
X15547Y762483D03*
Y770357D03*
Y778231D03*
X25389Y762483D03*
Y770357D03*
Y778231D03*
X7673Y766419D03*
Y774293D03*
Y782167D03*
X15547Y786105D03*
Y793979D03*
Y801853D03*
X25389Y786105D03*
Y793979D03*
Y801853D03*
X7673Y790041D03*
Y797915D03*
Y805790D03*
X15547Y809727D03*
Y817601D03*
Y825475D03*
X25389Y809727D03*
Y817601D03*
Y825475D03*
X7673Y813664D03*
Y821538D03*
Y829412D03*
X15547Y833349D03*
Y841223D03*
Y849097D03*
X25389Y833349D03*
Y841223D03*
Y849097D03*
X7673Y837286D03*
Y845160D03*
Y853034D03*
X15547Y856971D03*
Y864845D03*
Y872719D03*
X25389Y856971D03*
Y864845D03*
Y872719D03*
X7673Y860908D03*
Y868782D03*
Y876656D03*
X15547Y880593D03*
Y888467D03*
Y896341D03*
X25389Y880593D03*
Y888467D03*
Y896341D03*
X7673Y884530D03*
Y892404D03*
Y900278D03*
X15547Y904215D03*
Y912089D03*
Y919963D03*
X25389Y904215D03*
Y912089D03*
Y919963D03*
X7673Y908152D03*
Y916026D03*
Y923900D03*
X15547Y927837D03*
Y935711D03*
Y943585D03*
Y951459D03*
X25389Y927837D03*
Y935711D03*
Y943585D03*
Y951459D03*
X7673Y931774D03*
Y939648D03*
Y947522D03*
X15547Y959333D03*
Y967207D03*
Y975081D03*
X25389Y959333D03*
Y967207D03*
Y975081D03*
X7673Y955396D03*
Y963270D03*
Y971144D03*
Y979018D03*
Y994766D03*
X15547Y990829D03*
Y998703D03*
X25389Y990829D03*
Y998703D03*
X7673Y1002640D03*
Y1010514D03*
Y1018388D03*
X15547Y1006577D03*
Y1014451D03*
Y1022325D03*
X25389Y1006577D03*
Y1014451D03*
Y1022325D03*
X7673Y1026262D03*
X15547Y1030199D03*
X25389D03*
X15551Y1065629D03*
X25393D03*
X7677Y1061692D03*
Y1069566D03*
X15551Y1073503D03*
Y1081377D03*
Y1089251D03*
X25393Y1073503D03*
Y1081377D03*
Y1089251D03*
X7677Y1077440D03*
Y1085314D03*
Y1093188D03*
X15551Y1097125D03*
Y1104999D03*
Y1112873D03*
Y1120748D03*
X25393Y1097125D03*
Y1104999D03*
Y1112873D03*
Y1120748D03*
X7677Y1101062D03*
Y1108936D03*
Y1116810D03*
X15551Y1128622D03*
Y1136496D03*
Y1144370D03*
X25393Y1128622D03*
Y1136496D03*
Y1144370D03*
X7677Y1124684D03*
Y1132558D03*
Y1140432D03*
X15551Y1152244D03*
Y1160118D03*
Y1167992D03*
X25393Y1152244D03*
Y1160118D03*
Y1167992D03*
X7677Y1148306D03*
Y1156180D03*
Y1164055D03*
X15551Y1175866D03*
Y1183740D03*
Y1191614D03*
X25393Y1175866D03*
Y1183740D03*
Y1191614D03*
X7677Y1171929D03*
Y1179803D03*
Y1187677D03*
X15551Y1199488D03*
Y1207362D03*
Y1215236D03*
X25393Y1199488D03*
Y1207362D03*
Y1215236D03*
X7677Y1195551D03*
Y1203425D03*
Y1211299D03*
X15551Y1223110D03*
Y1230984D03*
Y1238858D03*
X25393Y1223110D03*
Y1230984D03*
Y1238858D03*
X7677Y1219173D03*
Y1227047D03*
Y1234921D03*
X15551Y1246732D03*
Y1254606D03*
Y1262480D03*
X25393Y1246732D03*
Y1254606D03*
Y1262480D03*
X7677Y1242795D03*
Y1250669D03*
Y1258543D03*
X15551Y1270354D03*
Y1278228D03*
Y1286102D03*
X25393Y1270354D03*
Y1278228D03*
Y1286102D03*
X7677Y1266417D03*
Y1274291D03*
Y1282165D03*
X15551Y1293976D03*
Y1301850D03*
Y1309724D03*
X25393Y1293976D03*
Y1301850D03*
Y1309724D03*
X7677Y1290039D03*
Y1297913D03*
Y1305787D03*
Y1313661D03*
X15551Y1317598D03*
Y1325472D03*
Y1333346D03*
X25393Y1317598D03*
Y1325472D03*
Y1333346D03*
X7677Y1321535D03*
Y1329409D03*
Y1337283D03*
Y1353031D03*
Y1360905D03*
X15551Y1349094D03*
Y1356968D03*
X25393Y1349094D03*
Y1356968D03*
X7677Y1368779D03*
Y1376653D03*
Y1384527D03*
X15551Y1364842D03*
Y1372716D03*
Y1380590D03*
X25393Y1364842D03*
Y1372716D03*
Y1380590D03*
X15551Y1388464D03*
X25393D03*
X33263Y727049D03*
Y734923D03*
Y742797D03*
Y750671D03*
Y758545D03*
Y766419D03*
Y774293D03*
Y782167D03*
Y790041D03*
Y797915D03*
Y805790D03*
Y813664D03*
Y821538D03*
Y829412D03*
Y837286D03*
Y845160D03*
Y853034D03*
Y860908D03*
Y868782D03*
Y876656D03*
Y884530D03*
Y892404D03*
Y900278D03*
Y908152D03*
Y916026D03*
Y923900D03*
Y931774D03*
Y939648D03*
Y947522D03*
Y955396D03*
Y963270D03*
Y971144D03*
Y979018D03*
Y994766D03*
Y1002640D03*
Y1010514D03*
Y1018388D03*
Y1026262D03*
X33267Y1061692D03*
Y1069566D03*
Y1077440D03*
Y1085314D03*
Y1093188D03*
Y1101062D03*
Y1108936D03*
Y1116810D03*
Y1124684D03*
Y1132558D03*
Y1140432D03*
Y1148306D03*
Y1156180D03*
Y1164055D03*
Y1171929D03*
Y1179803D03*
Y1187677D03*
Y1195551D03*
Y1203425D03*
Y1211299D03*
Y1219173D03*
Y1227047D03*
Y1234921D03*
Y1242795D03*
Y1250669D03*
Y1258543D03*
Y1266417D03*
Y1274291D03*
Y1282165D03*
Y1290039D03*
Y1297913D03*
Y1305787D03*
Y1313661D03*
Y1321535D03*
Y1329409D03*
Y1337283D03*
Y1353031D03*
Y1360905D03*
Y1368779D03*
Y1376653D03*
Y1384527D03*
G54D10*
X17735Y24953D03*
X27735D03*
X22735Y34953D03*
Y216976D03*
X27735Y206976D03*
X17735D03*
Y233811D03*
X27735D03*
X22735Y243811D03*
X27735Y415834D03*
X17735D03*
X22735Y425834D03*
Y1957291D03*
X27735Y1947291D03*
X17735D03*
X22735Y2061661D03*
X27735Y2051661D03*
X17735D03*
X37735Y24953D03*
X47735D03*
X32735Y34953D03*
X42735D03*
Y216976D03*
X32735D03*
X47735Y206976D03*
X37735D03*
Y233811D03*
X47735D03*
X32735Y243811D03*
X42735D03*
X47735Y415834D03*
X37735D03*
X42735Y425834D03*
X32735D03*
X42735Y1957291D03*
X32735D03*
X47735Y1947291D03*
X37735D03*
X42735Y2061661D03*
X32735D03*
X47735Y2051661D03*
X37735D03*
X52735Y34953D03*
Y216976D03*
Y243811D03*
Y425834D03*
Y1957291D03*
Y2061661D03*
G54D20*
X23402Y1668874D03*
Y1685410D03*
Y1701945D03*
Y1718480D03*
Y1735016D03*
Y1751551D03*
Y1768087D03*
Y1784622D03*
Y1817693D03*
Y1801158D03*
X45056Y1668874D03*
Y1718480D03*
Y1768087D03*
Y1817693D03*
G54D29*
X165975Y265783D03*
Y296140D03*
Y286803D03*
Y276298D03*
Y303868D03*
X157272Y604773D03*
Y633416D03*
Y613574D03*
Y624079D03*
Y641144D03*
X166699Y972924D03*
Y983439D03*
Y993944D03*
X166424Y1011298D03*
Y1003570D03*
X155749Y1307733D03*
Y1328753D03*
Y1318248D03*
Y1338090D03*
Y1345818D03*
X158492Y1667763D03*
Y1657248D03*
Y1695333D03*
Y1687605D03*
Y1678268D03*
X219214Y1287272D03*
X222732Y153964D03*
X232700D03*
X222732Y161692D03*
X232700Y170131D03*
Y161692D03*
X239746Y407393D03*
Y396878D03*
Y417898D03*
X243980Y754782D03*
X234012D03*
X243980Y762510D03*
Y770949D03*
X234012Y762510D03*
X224573Y2031480D03*
X234541D03*
X224573Y2020965D03*
X234541D03*
X224573Y2059050D03*
X234541Y2051322D03*
Y2059050D03*
X224573Y2041985D03*
Y2051322D03*
X234541Y2041985D03*
Y2067489D03*
X256566Y54944D03*
X264104D03*
X256566Y45572D03*
X264104D03*
X256566Y65449D03*
X264104D03*
X264861Y153964D03*
Y170131D03*
Y161692D03*
X264596Y268188D03*
Y259749D03*
Y252021D03*
X248714Y407536D03*
Y397021D03*
Y418041D03*
X263174Y855159D03*
Y862887D03*
Y871326D03*
X261219Y1124364D03*
Y1134879D03*
X251251Y1124364D03*
Y1134879D03*
X261219Y1145384D03*
X251251D03*
X259581Y1272430D03*
Y1282945D03*
Y1293450D03*
Y1302787D03*
Y1310515D03*
Y1318954D03*
X254718Y1697613D03*
Y1687108D03*
Y1676593D03*
X254457Y1722140D03*
X254718Y1714678D03*
Y1706950D03*
X278944Y601282D03*
Y609010D03*
Y617449D03*
X274399Y974386D03*
Y990553D03*
Y982114D03*
X286721Y1184312D03*
Y1192040D03*
X278182Y1184455D03*
Y1192183D03*
X286721Y1200479D03*
X273342Y1668347D03*
Y1652180D03*
Y1659908D03*
X270115Y2051322D03*
Y2059050D03*
Y2067489D03*
X300537Y516309D03*
Y524037D03*
Y532476D03*
X292569Y524323D03*
Y516595D03*
X304146Y661258D03*
Y652457D03*
Y681100D03*
Y671763D03*
Y688828D03*
Y697267D03*
X307194Y1020657D03*
X307078Y1007303D03*
X307274Y1001286D03*
X307143Y1014094D03*
X307129Y1027081D03*
X306999Y1033718D03*
X311936Y1192253D03*
Y1184525D03*
Y1200692D03*
X332775Y318634D03*
X332693Y311980D03*
X332775Y335272D03*
Y342461D03*
Y325935D03*
X332685Y348655D03*
X325139Y516632D03*
Y524360D03*
Y532799D03*
G54D30*
X165975Y312307D03*
X157272Y649583D03*
X166424Y1019737D03*
X155749Y1354257D03*
X158492Y1703772D03*
X243741Y153964D03*
Y170131D03*
Y161692D03*
X222732Y170131D03*
X234012Y770949D03*
X235465Y1301975D03*
X235600Y1308924D03*
X242961Y1301975D03*
X243096Y1308924D03*
X235465Y1294491D03*
X242961D03*
X235429Y1324285D03*
Y1332321D03*
X242925Y1324285D03*
Y1332321D03*
X235429Y1316842D03*
X242925D03*
X235429Y1339840D03*
X242925D03*
X224573Y2067489D03*
X253083Y153964D03*
Y170131D03*
Y161692D03*
X264596Y221664D03*
X252818D03*
X264596Y242684D03*
Y232179D03*
X252818Y242684D03*
Y232179D03*
Y268188D03*
Y252021D03*
Y259749D03*
X266040Y407146D03*
Y396631D03*
Y417651D03*
X257572Y396630D03*
Y407145D03*
Y417650D03*
X267166Y581440D03*
Y572639D03*
Y609010D03*
Y601282D03*
Y591945D03*
Y617449D03*
X255021Y754782D03*
Y762510D03*
Y770949D03*
X251396Y862887D03*
Y855159D03*
Y871326D03*
X262766Y949344D03*
Y967106D03*
Y959859D03*
X262621Y974386D03*
Y990553D03*
Y982114D03*
X261564Y1621823D03*
Y1642843D03*
Y1632338D03*
Y1668347D03*
Y1659908D03*
Y1652180D03*
X265759Y1697613D03*
Y1676593D03*
Y1687108D03*
X265498Y1722140D03*
X265759Y1714678D03*
Y1706950D03*
X258639Y1819074D03*
Y1812119D03*
Y1805203D03*
X258459Y1826219D03*
Y1840090D03*
Y1833135D03*
X245582Y2031480D03*
Y2020965D03*
X258337D03*
Y2031480D03*
X245582Y2041985D03*
Y2051322D03*
Y2059050D03*
X258337Y2051322D03*
Y2059050D03*
Y2041985D03*
Y2067489D03*
X245582D03*
X288102Y54944D03*
Y45572D03*
X271572Y54944D03*
X279754D03*
X271572Y45572D03*
X279754D03*
X288102Y65449D03*
X271572D03*
X279754D03*
X274531Y407289D03*
Y396774D03*
Y417794D03*
X278944Y581440D03*
Y572639D03*
Y591945D03*
X274544Y949344D03*
Y967106D03*
Y959859D03*
X279015Y1124077D03*
X288363Y1123935D03*
X279015Y1134592D03*
X288363Y1134450D03*
X269975Y1134735D03*
Y1124220D03*
X288363Y1144955D03*
X279015Y1145097D03*
X269975Y1145240D03*
X278182Y1200622D03*
X270622Y1282945D03*
Y1272430D03*
Y1293450D03*
Y1302787D03*
Y1310515D03*
Y1318954D03*
X273342Y1621823D03*
Y1642843D03*
Y1632338D03*
X270115Y2031480D03*
Y2020965D03*
Y2041985D03*
X307966Y516419D03*
Y524147D03*
Y532586D03*
X292569Y532762D03*
X315187Y652457D03*
Y661258D03*
Y681100D03*
Y671763D03*
Y688828D03*
Y697267D03*
X303159Y1184526D03*
Y1192254D03*
X294691Y1184526D03*
Y1192254D03*
X303159Y1200693D03*
X294691D03*
X301066Y1472954D03*
X300886Y1480099D03*
X301066Y1465999D03*
Y1459083D03*
X300886Y1493970D03*
Y1487015D03*
X316791Y524432D03*
Y516704D03*
Y532871D03*
X318235Y1020657D03*
X318315Y1001286D03*
X318119Y1007303D03*
X318184Y1014094D03*
X318170Y1027081D03*
X318040Y1033718D03*
X343816Y318634D03*
X343734Y311980D03*
X343816Y335272D03*
Y342461D03*
Y325935D03*
X343726Y348655D03*
G54D37*
X307086Y1883071D03*
G54D19*
X20468Y696341D03*
Y984333D03*
X20472Y1054606D03*
Y1342598D03*
G54D12*
X12735Y59953D03*
Y181976D03*
Y268811D03*
Y390834D03*
Y1922291D03*
Y2026661D03*
X57735Y59953D03*
Y181976D03*
Y268811D03*
Y390834D03*
Y1922291D03*
Y2026661D03*
G54D36*
X307086Y308267D03*
G54D14*
X13995Y543701D03*
Y1587992D03*
X58995Y543701D03*
Y1587992D03*
G54D27*
X163385Y27205D03*
Y202205D03*
Y377205D03*
X163386Y552205D03*
Y727205D03*
X163385Y902205D03*
Y1077205D03*
Y1252205D03*
Y1427205D03*
Y1602205D03*
Y1777205D03*
Y1952205D03*
X373385Y32520D03*
Y207520D03*
Y382520D03*
X373386Y557520D03*
Y732520D03*
X373385Y907520D03*
Y1082520D03*
Y1257520D03*
Y1432520D03*
Y1607520D03*
Y1782520D03*
Y1957520D03*
G54D38*
X359842Y78780D03*
Y253780D03*
Y428779D03*
Y603779D03*
Y778780D03*
Y953780D03*
Y1128779D03*
Y1303780D03*
Y1478780D03*
Y1653780D03*
Y1828779D03*
Y2003780D03*
G54D18*
X25389Y707364D03*
X7673Y703427D03*
X15547Y715238D03*
X25389D03*
X7673Y711301D03*
X33263Y703427D03*
Y711301D03*
Y719175D03*
G54D33*
X219214Y1301975D03*
X219349Y1308924D03*
X219214Y1294491D03*
X219178Y1324285D03*
Y1332321D03*
Y1316842D03*
Y1339840D03*
X226642Y1287272D03*
Y1301975D03*
X226777Y1308924D03*
X226642Y1294491D03*
X226606Y1324285D03*
Y1332321D03*
Y1316842D03*
Y1339840D03*
G54D35*
X263939Y1548010D03*
Y1534139D03*
Y1541055D03*
X250468Y1819074D03*
Y1812119D03*
Y1805203D03*
X267396Y1819077D03*
Y1805206D03*
Y1812122D03*
X250288Y1826219D03*
X267037Y1826222D03*
Y1833138D03*
Y1840093D03*
X250288Y1833135D03*
Y1840090D03*
X278400Y1548190D03*
X271534Y1548010D03*
X285995Y1548190D03*
X278400Y1534319D03*
Y1541235D03*
X271534Y1534139D03*
Y1541055D03*
X285995Y1534319D03*
Y1541235D03*
X309823Y1472957D03*
X309464Y1480102D03*
X309823Y1466002D03*
Y1459086D03*
X292715Y1480099D03*
X292895Y1472954D03*
Y1459083D03*
Y1465999D03*
X309464Y1493973D03*
Y1487018D03*
X292715Y1487015D03*
Y1493970D03*
X292754Y1917148D03*
X300349D03*
X292754Y1910232D03*
X300349D03*
X307215Y1910412D03*
X314810D03*
Y1917328D03*
X307215D03*
X292754Y1924103D03*
X300349D03*
X314810Y1924283D03*
X307215D03*
G54D34*
X253385Y21890D03*
Y32520D03*
X263385Y21890D03*
Y32520D03*
X253385Y196890D03*
X263385D03*
X253385Y207520D03*
X263385D03*
X253385Y371890D03*
X263385D03*
X253385Y382520D03*
X263385D03*
X253386Y546890D03*
Y557520D03*
X263386Y546890D03*
Y557520D03*
X253386Y721890D03*
Y732520D03*
X263386Y721890D03*
Y732520D03*
X253385Y896890D03*
X263385D03*
X253385Y907520D03*
X263385D03*
X253385Y1071890D03*
X263385D03*
X253385Y1082520D03*
X263385D03*
X253385Y1246890D03*
Y1257520D03*
X263385Y1246890D03*
Y1257520D03*
X253385Y1421890D03*
Y1432520D03*
X263385Y1421890D03*
Y1432520D03*
X253385Y1596890D03*
X263385D03*
X253385Y1607520D03*
X263385D03*
X253385Y1771890D03*
X263385D03*
X253385Y1782520D03*
X263385D03*
X253385Y1946890D03*
Y1957520D03*
X263385Y1946890D03*
Y1957520D03*
X273385Y21890D03*
Y32520D03*
X283385Y21890D03*
Y32520D03*
X273385Y196890D03*
X283385D03*
X273385Y207520D03*
X283385D03*
X273385Y371890D03*
X283385D03*
X273385Y382520D03*
X283385D03*
X273386Y546890D03*
Y557520D03*
X283386Y546890D03*
Y557520D03*
X273386Y721890D03*
Y732520D03*
X283386Y721890D03*
Y732520D03*
X273385Y896890D03*
X283385D03*
X273385Y907520D03*
X283385D03*
X273385Y1071890D03*
X283385D03*
X273385Y1082520D03*
X283385D03*
X273385Y1246890D03*
Y1257520D03*
X283385Y1246890D03*
Y1257520D03*
X273385Y1421890D03*
Y1432520D03*
X283385Y1421890D03*
Y1432520D03*
X273385Y1596890D03*
X283385D03*
X273385Y1607520D03*
X283385D03*
X273385Y1771890D03*
X283385D03*
X273385Y1782520D03*
X283385D03*
X273385Y1946890D03*
Y1957520D03*
X283385Y1946890D03*
Y1957520D03*
X293385Y21890D03*
Y32520D03*
X303385Y21890D03*
Y32520D03*
X313385D03*
Y21890D03*
X293385Y196890D03*
X303385D03*
X313385D03*
X293385Y207520D03*
X303385D03*
X313385D03*
X293385Y371890D03*
X303385D03*
X313385D03*
X293385Y382520D03*
X303385D03*
X313385D03*
X293386Y546890D03*
Y557520D03*
X303386Y546890D03*
Y557520D03*
X313386D03*
Y546890D03*
X293386Y721890D03*
Y732520D03*
X303386Y721890D03*
Y732520D03*
X313386D03*
Y721890D03*
X293385Y896890D03*
X303385D03*
X313385D03*
X293385Y907520D03*
X303385D03*
X313385D03*
X293385Y1071890D03*
X303385D03*
X313385D03*
X293385Y1082520D03*
X303385D03*
X313385D03*
X293385Y1246890D03*
Y1257520D03*
X303385Y1246890D03*
Y1257520D03*
X313385D03*
Y1246890D03*
X293385Y1421890D03*
Y1432520D03*
X303385Y1421890D03*
Y1432520D03*
X313385D03*
Y1421890D03*
X293385Y1596890D03*
X303385D03*
X313385D03*
X293385Y1607520D03*
X303385D03*
X313385D03*
X293385Y1771890D03*
X303385D03*
X313385D03*
X293385Y1782520D03*
X303385D03*
X313385D03*
X293385Y1946890D03*
Y1957520D03*
X303385Y1946890D03*
Y1957520D03*
X313385D03*
Y1946890D03*
X323385Y32520D03*
Y21890D03*
Y196890D03*
Y207520D03*
Y371890D03*
Y382520D03*
X323386Y557520D03*
Y546890D03*
Y732520D03*
Y721890D03*
X323385Y896890D03*
Y907520D03*
Y1071890D03*
Y1082520D03*
Y1257520D03*
Y1246890D03*
Y1432520D03*
Y1421890D03*
Y1596890D03*
Y1607520D03*
Y1771890D03*
Y1782520D03*
Y1957520D03*
Y1946890D03*
G54D23*
X65354Y114960D03*
Y464960D03*
Y814960D03*
Y1164960D03*
Y1514960D03*
Y1864960D03*
X307086Y127165D03*
Y477165D03*
Y827165D03*
Y1343504D03*
Y1693504D03*
X307087Y2043503D03*
G54D24*
X59127Y1257647D03*
X58356Y1279812D03*
X58416Y1272383D03*
X161339Y88108D03*
X161517Y436119D03*
X161479Y784141D03*
X161844Y1828225D03*
X292614Y1864565D03*
X323403Y1172804D03*
G54D26*
X119920Y218071D03*
Y228071D03*
Y238071D03*
Y248071D03*
Y258071D03*
Y268071D03*
Y278071D03*
Y288071D03*
Y298071D03*
Y308071D03*
Y318071D03*
Y328071D03*
Y566102D03*
Y576102D03*
Y586102D03*
Y596102D03*
Y606102D03*
Y616102D03*
Y626102D03*
Y636102D03*
Y646102D03*
Y656102D03*
Y666102D03*
Y676102D03*
Y914134D03*
Y924134D03*
Y934134D03*
Y944134D03*
Y954134D03*
Y964134D03*
Y974134D03*
Y984134D03*
Y994134D03*
Y1004134D03*
Y1014134D03*
Y1024134D03*
Y1262165D03*
Y1272165D03*
Y1282165D03*
Y1292165D03*
Y1302165D03*
Y1312165D03*
Y1322165D03*
Y1332165D03*
Y1342165D03*
Y1352165D03*
Y1362165D03*
Y1372165D03*
Y1610197D03*
Y1620197D03*
Y1630197D03*
Y1640197D03*
Y1650197D03*
Y1660197D03*
Y1670197D03*
Y1680197D03*
Y1690197D03*
Y1700197D03*
Y1710197D03*
Y1720197D03*
Y1958228D03*
Y1968228D03*
Y1978228D03*
Y1988228D03*
Y1998228D03*
Y2008228D03*
Y2018228D03*
Y2028228D03*
Y2038228D03*
Y2048228D03*
Y2058228D03*
Y2068228D03*
X139920Y228071D03*
Y218071D03*
Y248071D03*
Y238071D03*
Y268071D03*
Y258071D03*
Y298071D03*
Y288071D03*
Y278071D03*
Y318071D03*
Y308071D03*
Y328071D03*
Y566102D03*
Y586102D03*
Y576102D03*
Y606102D03*
Y596102D03*
Y636102D03*
Y626102D03*
Y616102D03*
Y656102D03*
Y646102D03*
Y676102D03*
Y666102D03*
Y924134D03*
Y914134D03*
Y944134D03*
Y934134D03*
Y974134D03*
Y964134D03*
Y954134D03*
Y994134D03*
Y984134D03*
Y1024134D03*
Y1014134D03*
Y1004134D03*
Y1262165D03*
Y1282165D03*
Y1272165D03*
Y1312165D03*
Y1302165D03*
Y1292165D03*
Y1332165D03*
Y1322165D03*
Y1362165D03*
Y1352165D03*
Y1342165D03*
Y1372165D03*
Y1620197D03*
Y1610197D03*
Y1650197D03*
Y1640197D03*
Y1630197D03*
Y1670197D03*
Y1660197D03*
Y1700197D03*
Y1690197D03*
Y1680197D03*
Y1720197D03*
Y1710197D03*
Y1958228D03*
Y1988228D03*
Y1978228D03*
Y1968228D03*
Y2008228D03*
Y1998228D03*
Y2038228D03*
Y2028228D03*
Y2018228D03*
Y2058228D03*
Y2048228D03*
Y2068228D03*
G54D32*
X203542Y73105D03*
X204069Y152050D03*
X204137Y247568D03*
X204597Y331786D03*
X203541Y421732D03*
X204333Y506517D03*
X206668Y598130D03*
X204596Y681645D03*
X205626Y774526D03*
X205386Y856244D03*
X210091Y947202D03*
X209296Y1032544D03*
X205030Y1122856D03*
X205122Y1206233D03*
X205626Y1299104D03*
X204332Y1380966D03*
X203243Y1474162D03*
X204859Y1557277D03*
X205923Y1648177D03*
X205387Y1731351D03*
X205310Y1823227D03*
X204069Y1900420D03*
X205905Y1998730D03*
X205310Y2043388D03*
G54D21*
X45056Y1685410D03*
Y1701945D03*
Y1735016D03*
Y1751551D03*
Y1784622D03*
Y1801158D03*
%LPC*%
G75*
G54D39*
G01X-723776Y2987387D02*
Y-376795D01*
Y-489221D01*
X1782976D01*
Y-376795D01*
Y2987387D01*
X-723776D01*
G01X-4000Y-62500D02*
Y-137500D01*
X496000D01*
Y-62500D01*
X-4000D01*
G01X8000Y-127500D02*
Y-132500D01*
G01X6543Y-127500D02*
X9457D01*
G01X14367Y-132500D02*
X11833D01*
Y-127500D01*
X14367D01*
G01X13353Y-129917D02*
X11833D01*
G01X16933Y-127500D02*
Y-132500D01*
X19467D01*
G01X23300Y-132667D02*
X23173Y-132583D01*
Y-132417D01*
X23300Y-132333D01*
X23427Y-132417D01*
Y-132583D01*
X23300Y-132667D01*
G01Y-130417D02*
X23173Y-130333D01*
Y-130167D01*
X23300Y-130083D01*
X23427Y-130167D01*
Y-130333D01*
X23300Y-130417D01*
G01X28083Y-134167D02*
X27450Y-133333D01*
X27133Y-132500D01*
Y-129167D01*
X27450Y-128333D01*
X28083Y-127500D01*
G01X33500D02*
X32993Y-127667D01*
X32613Y-128083D01*
X32360Y-128583D01*
X32170Y-129250D01*
X32107Y-130000D01*
X32170Y-130750D01*
X32360Y-131417D01*
X32613Y-131917D01*
X32993Y-132333D01*
X33500Y-132500D01*
X34007Y-132333D01*
X34387Y-131917D01*
X34640Y-131417D01*
X34830Y-130750D01*
X34893Y-130000D01*
X34830Y-129250D01*
X34640Y-128583D01*
X34387Y-128083D01*
X34007Y-127667D01*
X33500Y-127500D01*
G01X37207Y-131500D02*
X37587Y-132083D01*
X38093Y-132417D01*
X38663Y-132500D01*
X39170Y-132417D01*
X39677Y-132000D01*
X39993Y-131500D01*
X40057Y-131000D01*
X39930Y-130417D01*
X39487Y-130000D01*
X39043Y-129833D01*
X38473D01*
G01X39043D02*
X39423Y-129583D01*
X39740Y-129167D01*
X39867Y-128667D01*
X39740Y-128167D01*
X39423Y-127750D01*
X38853Y-127500D01*
X38283Y-127583D01*
X37713Y-127917D01*
G01X44017Y-134167D02*
X44650Y-133333D01*
X44967Y-132500D01*
Y-129167D01*
X44650Y-128333D01*
X44017Y-127500D01*
G01X47407Y-131500D02*
X47787Y-132083D01*
X48293Y-132417D01*
X48863Y-132500D01*
X49370Y-132417D01*
X49877Y-132000D01*
X50193Y-131500D01*
X50257Y-131000D01*
X50130Y-130417D01*
X49687Y-130000D01*
X49243Y-129833D01*
X48673D01*
G01X49243D02*
X49623Y-129583D01*
X49940Y-129167D01*
X50067Y-128667D01*
X49940Y-128167D01*
X49623Y-127750D01*
X49053Y-127500D01*
X48483Y-127583D01*
X47913Y-127917D01*
G01X52697Y-128333D02*
X53077Y-127833D01*
X53520Y-127583D01*
X54027Y-127500D01*
X54660Y-127667D01*
X55103Y-128083D01*
X55230Y-128583D01*
X55167Y-129083D01*
X54913Y-129500D01*
X53647Y-130333D01*
X53077Y-130917D01*
X52697Y-131750D01*
X52570Y-132500D01*
X55230D01*
G01X58873D02*
X59000Y-131417D01*
X59190Y-130500D01*
X59443Y-129667D01*
X59760Y-128750D01*
X60267Y-127500D01*
X57733D01*
G01X63277Y-130833D02*
X64923D01*
G01X67997Y-128333D02*
X68377Y-127833D01*
X68820Y-127583D01*
X69327Y-127500D01*
X69960Y-127667D01*
X70403Y-128083D01*
X70530Y-128583D01*
X70467Y-129083D01*
X70213Y-129500D01*
X68947Y-130333D01*
X68377Y-130917D01*
X67997Y-131750D01*
X67870Y-132500D01*
X70530D01*
G01X72907Y-131500D02*
X73287Y-132083D01*
X73793Y-132417D01*
X74363Y-132500D01*
X74870Y-132417D01*
X75377Y-132000D01*
X75693Y-131500D01*
X75757Y-131000D01*
X75630Y-130417D01*
X75187Y-130000D01*
X74743Y-129833D01*
X74173D01*
G01X74743D02*
X75123Y-129583D01*
X75440Y-129167D01*
X75567Y-128667D01*
X75440Y-128167D01*
X75123Y-127750D01*
X74553Y-127500D01*
X73983Y-127583D01*
X73413Y-127917D01*
G01X80160Y-132500D02*
Y-127500D01*
X77817Y-131083D01*
X80983D01*
G01X83107Y-131750D02*
X83487Y-132167D01*
X83930Y-132417D01*
X84500Y-132500D01*
X85070Y-132333D01*
X85513Y-132000D01*
X85830Y-131417D01*
X85893Y-130750D01*
X85767Y-130083D01*
X85450Y-129667D01*
X85007Y-129333D01*
X84563Y-129250D01*
X84120Y-129333D01*
X83550Y-129667D01*
X83740Y-127500D01*
X85450D01*
G01X93497Y-132500D02*
Y-127500D01*
X95903D01*
G01X95017Y-129917D02*
X93497D01*
G01X98217Y-132500D02*
X99800Y-127500D01*
X101383Y-132500D01*
G01X100813Y-130750D02*
X98787D01*
G01X103570Y-132500D02*
X106230Y-127500D01*
G01X103570D02*
X106230Y-132500D01*
G01X110000Y-132667D02*
X109873Y-132583D01*
Y-132417D01*
X110000Y-132333D01*
X110127Y-132417D01*
Y-132583D01*
X110000Y-132667D01*
G01Y-130417D02*
X109873Y-130333D01*
Y-130167D01*
X110000Y-130083D01*
X110127Y-130167D01*
Y-130333D01*
X110000Y-130417D01*
G01X114783Y-134167D02*
X114150Y-133333D01*
X113833Y-132500D01*
Y-129167D01*
X114150Y-128333D01*
X114783Y-127500D01*
G01X120200D02*
X119693Y-127667D01*
X119313Y-128083D01*
X119060Y-128583D01*
X118870Y-129250D01*
X118807Y-130000D01*
X118870Y-130750D01*
X119060Y-131417D01*
X119313Y-131917D01*
X119693Y-132333D01*
X120200Y-132500D01*
X120707Y-132333D01*
X121087Y-131917D01*
X121340Y-131417D01*
X121530Y-130750D01*
X121593Y-130000D01*
X121530Y-129250D01*
X121340Y-128583D01*
X121087Y-128083D01*
X120707Y-127667D01*
X120200Y-127500D01*
G01X123907Y-131500D02*
X124287Y-132083D01*
X124793Y-132417D01*
X125363Y-132500D01*
X125870Y-132417D01*
X126377Y-132000D01*
X126693Y-131500D01*
X126757Y-131000D01*
X126630Y-130417D01*
X126187Y-130000D01*
X125743Y-129833D01*
X125173D01*
G01X125743D02*
X126123Y-129583D01*
X126440Y-129167D01*
X126567Y-128667D01*
X126440Y-128167D01*
X126123Y-127750D01*
X125553Y-127500D01*
X124983Y-127583D01*
X124413Y-127917D01*
G01X130717Y-134167D02*
X131350Y-133333D01*
X131667Y-132500D01*
Y-129167D01*
X131350Y-128333D01*
X130717Y-127500D01*
G01X134107Y-131500D02*
X134487Y-132083D01*
X134993Y-132417D01*
X135563Y-132500D01*
X136070Y-132417D01*
X136577Y-132000D01*
X136893Y-131500D01*
X136957Y-131000D01*
X136830Y-130417D01*
X136387Y-130000D01*
X135943Y-129833D01*
X135373D01*
G01X135943D02*
X136323Y-129583D01*
X136640Y-129167D01*
X136767Y-128667D01*
X136640Y-128167D01*
X136323Y-127750D01*
X135753Y-127500D01*
X135183Y-127583D01*
X134613Y-127917D01*
G01X139523Y-131917D02*
X139967Y-132333D01*
X140473Y-132500D01*
X140980Y-132333D01*
X141423Y-131833D01*
X141740Y-131083D01*
X141867Y-130333D01*
Y-129417D01*
X141740Y-128667D01*
X141423Y-128000D01*
X141043Y-127667D01*
X140600Y-127500D01*
X140093Y-127667D01*
X139713Y-128000D01*
X139460Y-128500D01*
X139333Y-129167D01*
X139460Y-129750D01*
X139777Y-130333D01*
X140157Y-130667D01*
X140600Y-130750D01*
X141107Y-130583D01*
X141487Y-130167D01*
X141867Y-129417D01*
G01X145573Y-132500D02*
X145700Y-131417D01*
X145890Y-130500D01*
X146143Y-129667D01*
X146460Y-128750D01*
X146967Y-127500D01*
X144433D01*
G01X149977Y-130833D02*
X151623D01*
G01X154507Y-131500D02*
X154887Y-132083D01*
X155393Y-132417D01*
X155963Y-132500D01*
X156470Y-132417D01*
X156977Y-132000D01*
X157293Y-131500D01*
X157357Y-131000D01*
X157230Y-130417D01*
X156787Y-130000D01*
X156343Y-129833D01*
X155773D01*
G01X156343D02*
X156723Y-129583D01*
X157040Y-129167D01*
X157167Y-128667D01*
X157040Y-128167D01*
X156723Y-127750D01*
X156153Y-127500D01*
X155583Y-127583D01*
X155013Y-127917D01*
G01X159797Y-130417D02*
X160240Y-129833D01*
X160620Y-129500D01*
X161127Y-129333D01*
X161570Y-129500D01*
X161887Y-129833D01*
X162140Y-130333D01*
X162203Y-130917D01*
X162140Y-131417D01*
X161887Y-131917D01*
X161507Y-132333D01*
X161063Y-132500D01*
X160557Y-132333D01*
X160113Y-131833D01*
X159860Y-131083D01*
X159797Y-130250D01*
X159923Y-129167D01*
X160113Y-128583D01*
X160430Y-128000D01*
X160873Y-127583D01*
X161317Y-127500D01*
X161760Y-127667D01*
X162077Y-128083D01*
G01X166100Y-132500D02*
Y-127500D01*
X165340Y-128500D01*
G01Y-132500D02*
X166860D01*
G01X171960D02*
Y-127500D01*
X169617Y-131083D01*
X172783D01*
G01X191000Y-62500D02*
Y-137500D01*
G01Y-112500D02*
X294000D01*
Y-87500D01*
G01X191000D02*
X294000D01*
G01X301507Y-122500D02*
Y-117500D01*
X302773D01*
X303280Y-117750D01*
X303660Y-118083D01*
X303977Y-118583D01*
X304230Y-119167D01*
X304293Y-120000D01*
X304230Y-120833D01*
X303977Y-121417D01*
X303660Y-121917D01*
X303280Y-122250D01*
X302773Y-122500D01*
X301507D01*
G01X306417D02*
X308000Y-117500D01*
X309583Y-122500D01*
G01X309013Y-120750D02*
X306987D01*
G01X313100Y-117500D02*
Y-122500D01*
G01X311643Y-117500D02*
X314557D01*
G01X319467Y-122500D02*
X316933D01*
Y-117500D01*
X319467D01*
G01X318453Y-119917D02*
X316933D01*
G01X323300Y-122667D02*
X323173Y-122583D01*
Y-122417D01*
X323300Y-122333D01*
X323427Y-122417D01*
Y-122583D01*
X323300Y-122667D01*
G01Y-120417D02*
X323173Y-120333D01*
Y-120167D01*
X323300Y-120083D01*
X323427Y-120167D01*
Y-120333D01*
X323300Y-120417D01*
G01X296000Y-62500D02*
Y-137500D01*
G01X294000Y-62500D02*
Y-137500D01*
G01X301633Y-97500D02*
Y-92500D01*
X303153D01*
X303660Y-92750D01*
X304040Y-93333D01*
X304167Y-94000D01*
X304040Y-94667D01*
X303723Y-95167D01*
X303153Y-95417D01*
X301633D01*
G01X306860Y-97667D02*
X309140Y-92500D01*
G01X311643Y-97500D02*
Y-92500D01*
X314557Y-97500D01*
Y-92500D01*
G01X318200Y-97667D02*
X318073Y-97583D01*
Y-97417D01*
X318200Y-97333D01*
X318327Y-97417D01*
Y-97583D01*
X318200Y-97667D01*
G01Y-95417D02*
X318073Y-95333D01*
Y-95167D01*
X318200Y-95083D01*
X318327Y-95167D01*
Y-95333D01*
X318200Y-95417D01*
G01X296000Y-112500D02*
X496000D01*
G01X301633Y-72500D02*
Y-67500D01*
X303153D01*
X303660Y-67750D01*
X304040Y-68333D01*
X304167Y-69000D01*
X304040Y-69667D01*
X303723Y-70167D01*
X303153Y-70417D01*
X301633D01*
G01X306733Y-72500D02*
Y-67500D01*
X308317D01*
X308823Y-67750D01*
X309140Y-68083D01*
X309267Y-68750D01*
X309140Y-69417D01*
X308760Y-69833D01*
X308317Y-70083D01*
X306733D01*
G01X308317D02*
X309267Y-72500D01*
G01X313100D02*
X312593Y-72417D01*
X312150Y-72083D01*
X311770Y-71583D01*
X311517Y-71000D01*
X311390Y-70333D01*
Y-69667D01*
X311517Y-69000D01*
X311770Y-68417D01*
X312150Y-67917D01*
X312593Y-67583D01*
X313100Y-67500D01*
X313607Y-67583D01*
X314050Y-67917D01*
X314430Y-68417D01*
X314683Y-69000D01*
X314810Y-69667D01*
Y-70333D01*
X314683Y-71000D01*
X314430Y-71583D01*
X314050Y-72083D01*
X313607Y-72417D01*
X313100Y-72500D01*
G01X316933Y-71500D02*
X317250Y-72000D01*
X317630Y-72333D01*
X318073Y-72500D01*
X318580Y-72333D01*
X318960Y-72000D01*
X319340Y-71500D01*
X319467Y-70833D01*
Y-67500D01*
G01X324567Y-72500D02*
X322033D01*
Y-67500D01*
X324567D01*
G01X323553Y-69917D02*
X322033D01*
G01X329793Y-67917D02*
X329413Y-67667D01*
X328970Y-67500D01*
X328463D01*
X327893Y-67750D01*
X327450Y-68167D01*
X327133Y-68667D01*
X326880Y-69500D01*
X326817Y-70250D01*
X326943Y-71000D01*
X327133Y-71500D01*
X327513Y-72000D01*
X327957Y-72333D01*
X328400Y-72500D01*
X328843D01*
X329287Y-72333D01*
X329667Y-72083D01*
X329983Y-71750D01*
G01X333500Y-67500D02*
Y-72500D01*
G01X332043Y-67500D02*
X334957D01*
G01X338600Y-72667D02*
X338473Y-72583D01*
Y-72417D01*
X338600Y-72333D01*
X338727Y-72417D01*
Y-72583D01*
X338600Y-72667D01*
G01Y-70417D02*
X338473Y-70333D01*
Y-70167D01*
X338600Y-70083D01*
X338727Y-70167D01*
Y-70333D01*
X338600Y-70417D01*
G01X296000Y-87500D02*
X496000D01*
G01X411000Y-112500D02*
Y-137500D01*
G01X416633Y-122500D02*
Y-117500D01*
X418217D01*
X418723Y-117750D01*
X419040Y-118083D01*
X419167Y-118750D01*
X419040Y-119417D01*
X418660Y-119833D01*
X418217Y-120083D01*
X416633D01*
G01X418217D02*
X419167Y-122500D01*
G01X424267D02*
X421733D01*
Y-117500D01*
X424267D01*
G01X423253Y-119917D02*
X421733D01*
G01X426517Y-117500D02*
X428100Y-122500D01*
X429683Y-117500D01*
G01X433200Y-122667D02*
X433073Y-122583D01*
Y-122417D01*
X433200Y-122333D01*
X433327Y-122417D01*
Y-122583D01*
X433200Y-122667D01*
G01Y-120417D02*
X433073Y-120333D01*
Y-120167D01*
X433200Y-120083D01*
X433327Y-120167D01*
Y-120333D01*
X433200Y-120417D01*
G01X460000Y-112500D02*
Y-137500D01*
G01X-723776Y2987387D02*
Y-376795D01*
Y-489221D01*
X1782976D01*
Y-376795D01*
Y2987387D01*
X-723776D01*
G01X6705Y-124160D02*
X7332Y-124685D01*
X8037Y-125000D01*
X8663D01*
X9290Y-124685D01*
X9760Y-124160D01*
X9995Y-123425D01*
X9838Y-122690D01*
X9447Y-122060D01*
X8742Y-121640D01*
X7802Y-121430D01*
X7253Y-121010D01*
X7018Y-120275D01*
X7175Y-119540D01*
X7567Y-119015D01*
X8115Y-118700D01*
X8663D01*
X9212Y-118910D01*
X9682Y-119435D01*
G01X13005Y-125000D02*
Y-118700D01*
G01X16295D02*
Y-125000D01*
G01Y-121850D02*
X13005D01*
G01X20010Y-118700D02*
X21890D01*
G01X20950D02*
Y-125000D01*
G01X20010D02*
X21890D01*
G01X28817D02*
X25683D01*
Y-118700D01*
X28817D01*
G01X27563Y-121745D02*
X25683D01*
G01X31748Y-125000D02*
Y-118700D01*
X35352Y-125000D01*
Y-118700D01*
G01X39693Y-126155D02*
X40007Y-124790D01*
G01X46150Y-118700D02*
Y-125000D01*
G01X44348Y-118700D02*
X47952D01*
G01X50492Y-125000D02*
X52450Y-118700D01*
X54408Y-125000D01*
G01X53703Y-122795D02*
X51197D01*
G01X57810Y-118700D02*
X59690D01*
G01X58750D02*
Y-125000D01*
G01X57810D02*
X59690D01*
G01X62700Y-118700D02*
X63797Y-125000D01*
X65050Y-118700D01*
X66303Y-125000D01*
X67400Y-118700D01*
G01X69392Y-125000D02*
X71350Y-118700D01*
X73308Y-125000D01*
G01X72603Y-122795D02*
X70097D01*
G01X75848Y-125000D02*
Y-118700D01*
X79452Y-125000D01*
Y-118700D01*
G01X88683Y-125000D02*
Y-118700D01*
X90642D01*
X91268Y-119015D01*
X91660Y-119435D01*
X91817Y-120275D01*
X91660Y-121115D01*
X91190Y-121640D01*
X90642Y-121955D01*
X88683D01*
G01X90642D02*
X91817Y-125000D01*
G01X96550Y-125210D02*
X96393Y-125105D01*
Y-124895D01*
X96550Y-124790D01*
X96707Y-124895D01*
Y-125105D01*
X96550Y-125210D01*
G01X102850Y-125000D02*
X102223Y-124895D01*
X101675Y-124475D01*
X101205Y-123845D01*
X100892Y-123110D01*
X100735Y-122270D01*
Y-121430D01*
X100892Y-120590D01*
X101205Y-119855D01*
X101675Y-119225D01*
X102223Y-118805D01*
X102850Y-118700D01*
X103477Y-118805D01*
X104025Y-119225D01*
X104495Y-119855D01*
X104808Y-120590D01*
X104965Y-121430D01*
Y-122270D01*
X104808Y-123110D01*
X104495Y-123845D01*
X104025Y-124475D01*
X103477Y-124895D01*
X102850Y-125000D01*
G01X109150Y-125210D02*
X108993Y-125105D01*
Y-124895D01*
X109150Y-124790D01*
X109307Y-124895D01*
Y-125105D01*
X109150Y-125210D01*
G01X117173Y-119225D02*
X116703Y-118910D01*
X116155Y-118700D01*
X115528D01*
X114823Y-119015D01*
X114275Y-119540D01*
X113883Y-120170D01*
X113570Y-121220D01*
X113492Y-122165D01*
X113648Y-123110D01*
X113883Y-123740D01*
X114353Y-124370D01*
X114902Y-124790D01*
X115450Y-125000D01*
X115998D01*
X116547Y-124790D01*
X117017Y-124475D01*
X117408Y-124055D01*
G01X121750Y-125210D02*
X121593Y-125105D01*
Y-124895D01*
X121750Y-124790D01*
X121907Y-124895D01*
Y-125105D01*
X121750Y-125210D01*
G01X6627Y-115000D02*
Y-108700D01*
G01X9603D02*
X6627Y-112585D01*
G01X10073Y-115000D02*
X7958Y-110800D01*
G01X12927Y-108700D02*
Y-113215D01*
X13240Y-114160D01*
X13867Y-114790D01*
X14650Y-115000D01*
X15433Y-114790D01*
X16060Y-114160D01*
X16373Y-113215D01*
Y-108700D01*
G01X22517Y-115000D02*
X19383D01*
Y-108700D01*
X22517D01*
G01X21263Y-111745D02*
X19383D01*
G01X26310Y-108700D02*
X28190D01*
G01X27250D02*
Y-115000D01*
G01X26310D02*
X28190D01*
G01X38205Y-114160D02*
X38832Y-114685D01*
X39537Y-115000D01*
X40163D01*
X40790Y-114685D01*
X41260Y-114160D01*
X41495Y-113425D01*
X41338Y-112690D01*
X40947Y-112060D01*
X40242Y-111640D01*
X39302Y-111430D01*
X38753Y-111010D01*
X38518Y-110275D01*
X38675Y-109540D01*
X39067Y-109015D01*
X39615Y-108700D01*
X40163D01*
X40712Y-108910D01*
X41182Y-109435D01*
G01X44505Y-115000D02*
Y-108700D01*
G01X47795D02*
Y-115000D01*
G01Y-111850D02*
X44505D01*
G01X50492Y-115000D02*
X52450Y-108700D01*
X54408Y-115000D01*
G01X53703Y-112795D02*
X51197D01*
G01X56948Y-115000D02*
Y-108700D01*
X60552Y-115000D01*
Y-108700D01*
G01X69705Y-115000D02*
Y-108700D01*
G01X72995D02*
Y-115000D01*
G01Y-111850D02*
X69705D01*
G01X76005Y-114160D02*
X76632Y-114685D01*
X77337Y-115000D01*
X77963D01*
X78590Y-114685D01*
X79060Y-114160D01*
X79295Y-113425D01*
X79138Y-112690D01*
X78747Y-112060D01*
X78042Y-111640D01*
X77102Y-111430D01*
X76553Y-111010D01*
X76318Y-110275D01*
X76475Y-109540D01*
X76867Y-109015D01*
X77415Y-108700D01*
X77963D01*
X78512Y-108910D01*
X78982Y-109435D01*
G01X83010Y-108700D02*
X84890D01*
G01X83950D02*
Y-115000D01*
G01X83010D02*
X84890D01*
G01X88292D02*
X90250Y-108700D01*
X92208Y-115000D01*
G01X91503Y-112795D02*
X88997D01*
G01X94748Y-115000D02*
Y-108700D01*
X98352Y-115000D01*
Y-108700D01*
G01X103320Y-111850D02*
X104887D01*
Y-113740D01*
X104417Y-114370D01*
X103868Y-114790D01*
X103085Y-115000D01*
X102302Y-114790D01*
X101753Y-114370D01*
X101283Y-113740D01*
X100970Y-113005D01*
X100813Y-112165D01*
Y-111430D01*
X100970Y-110800D01*
X101283Y-110065D01*
X101753Y-109435D01*
X102223Y-109015D01*
X102850Y-108700D01*
X103398D01*
X104025Y-108910D01*
X104495Y-109330D01*
G01X108993Y-116155D02*
X109307Y-114790D01*
G01X115450Y-108700D02*
Y-115000D01*
G01X113648Y-108700D02*
X117252D01*
G01X119792Y-115000D02*
X121750Y-108700D01*
X123708Y-115000D01*
G01X123003Y-112795D02*
X120497D01*
G01X128050Y-115000D02*
X127423Y-114895D01*
X126875Y-114475D01*
X126405Y-113845D01*
X126092Y-113110D01*
X125935Y-112270D01*
Y-111430D01*
X126092Y-110590D01*
X126405Y-109855D01*
X126875Y-109225D01*
X127423Y-108805D01*
X128050Y-108700D01*
X128677Y-108805D01*
X129225Y-109225D01*
X129695Y-109855D01*
X130008Y-110590D01*
X130165Y-111430D01*
Y-112270D01*
X130008Y-113110D01*
X129695Y-113845D01*
X129225Y-114475D01*
X128677Y-114895D01*
X128050Y-115000D01*
G01X140650D02*
Y-112165D01*
X139083Y-108700D01*
G01X142217D02*
X140650Y-112165D01*
G01X145227Y-108700D02*
Y-113215D01*
X145540Y-114160D01*
X146167Y-114790D01*
X146950Y-115000D01*
X147733Y-114790D01*
X148360Y-114160D01*
X148673Y-113215D01*
Y-108700D01*
G01X151292Y-115000D02*
X153250Y-108700D01*
X155208Y-115000D01*
G01X154503Y-112795D02*
X151997D01*
G01X157748Y-115000D02*
Y-108700D01*
X161352Y-115000D01*
Y-108700D01*
G01X30650Y-92300D02*
X28130Y-91883D01*
X25925Y-90217D01*
X24035Y-87717D01*
X22775Y-84800D01*
X22145Y-81467D01*
Y-78133D01*
X22775Y-74800D01*
X24035Y-71883D01*
X25925Y-69384D01*
X28130Y-67717D01*
X30650Y-67300D01*
X33170Y-67717D01*
X35375Y-69384D01*
X37265Y-71883D01*
X38525Y-74800D01*
X39155Y-78133D01*
Y-81467D01*
X38525Y-84800D01*
X37265Y-87717D01*
X35375Y-90217D01*
X33170Y-91883D01*
X30650Y-92300D01*
G01X33170Y-85633D02*
X36950Y-92300D01*
G01X50495Y-75634D02*
Y-87300D01*
X51755Y-90217D01*
X53645Y-91883D01*
X55850Y-92300D01*
X58055Y-91883D01*
X59945Y-90217D01*
X61205Y-87300D01*
G01Y-92300D02*
Y-75634D01*
G01X86720Y-92300D02*
Y-75634D01*
G01Y-78550D02*
X85460Y-76884D01*
X83570Y-76050D01*
X81365Y-75634D01*
X79160Y-76467D01*
X77270Y-78133D01*
X76010Y-80634D01*
X75380Y-83967D01*
X76010Y-87300D01*
X77270Y-89801D01*
X79160Y-91467D01*
X81365Y-92300D01*
X83570Y-91883D01*
X85460Y-90634D01*
X86720Y-88967D01*
G01X100895Y-92300D02*
Y-75634D01*
G01Y-79800D02*
X102155Y-77717D01*
X104045Y-76050D01*
X106565Y-75634D01*
X108770Y-76050D01*
X110660Y-77717D01*
X111605Y-80634D01*
Y-92300D01*
G01X131450Y-67300D02*
Y-92300D01*
G01X127040Y-75634D02*
X135860D01*
G01X162320Y-92300D02*
Y-75634D01*
G01Y-78550D02*
X161060Y-76884D01*
X159170Y-76050D01*
X156965Y-75634D01*
X154760Y-76467D01*
X152870Y-78133D01*
X151610Y-80634D01*
X150980Y-83967D01*
X151610Y-87300D01*
X152870Y-89801D01*
X154760Y-91467D01*
X156965Y-92300D01*
X159170Y-91883D01*
X161060Y-90634D01*
X162320Y-88967D01*
G01X6548Y-105000D02*
Y-98700D01*
X10152Y-105000D01*
Y-98700D01*
G01X14650Y-105000D02*
X14023Y-104895D01*
X13475Y-104475D01*
X13005Y-103845D01*
X12692Y-103110D01*
X12535Y-102270D01*
Y-101430D01*
X12692Y-100590D01*
X13005Y-99855D01*
X13475Y-99225D01*
X14023Y-98805D01*
X14650Y-98700D01*
X15277Y-98805D01*
X15825Y-99225D01*
X16295Y-99855D01*
X16608Y-100590D01*
X16765Y-101430D01*
Y-102270D01*
X16608Y-103110D01*
X16295Y-103845D01*
X15825Y-104475D01*
X15277Y-104895D01*
X14650Y-105000D01*
G01X20950Y-105210D02*
X20793Y-105105D01*
Y-104895D01*
X20950Y-104790D01*
X21107Y-104895D01*
Y-105105D01*
X20950Y-105210D01*
G01X27250Y-105000D02*
Y-98700D01*
X26310Y-99960D01*
G01Y-105000D02*
X28190D01*
G01X33550D02*
X34098Y-104895D01*
X34725Y-104580D01*
X35117Y-104055D01*
X35273Y-103320D01*
X35117Y-102585D01*
X34647Y-101955D01*
X33942Y-101640D01*
X33158D01*
X32688Y-101430D01*
X32297Y-100905D01*
X32140Y-100170D01*
X32375Y-99435D01*
X32923Y-98910D01*
X33550Y-98700D01*
X34177Y-98910D01*
X34725Y-99435D01*
X34960Y-100170D01*
X34803Y-100905D01*
X34412Y-101430D01*
X33942Y-101640D01*
X33158D01*
X32453Y-101955D01*
X31983Y-102585D01*
X31827Y-103320D01*
X31983Y-104055D01*
X32375Y-104580D01*
X33002Y-104895D01*
X33550Y-105000D01*
G01X39850D02*
X40398Y-104895D01*
X41025Y-104580D01*
X41417Y-104055D01*
X41573Y-103320D01*
X41417Y-102585D01*
X40947Y-101955D01*
X40242Y-101640D01*
X39458D01*
X38988Y-101430D01*
X38597Y-100905D01*
X38440Y-100170D01*
X38675Y-99435D01*
X39223Y-98910D01*
X39850Y-98700D01*
X40477Y-98910D01*
X41025Y-99435D01*
X41260Y-100170D01*
X41103Y-100905D01*
X40712Y-101430D01*
X40242Y-101640D01*
X39458D01*
X38753Y-101955D01*
X38283Y-102585D01*
X38127Y-103320D01*
X38283Y-104055D01*
X38675Y-104580D01*
X39302Y-104895D01*
X39850Y-105000D01*
G01X45993Y-106155D02*
X46307Y-104790D01*
G01X50100Y-98700D02*
X51197Y-105000D01*
X52450Y-98700D01*
X53703Y-105000D01*
X54800Y-98700D01*
G01X60317Y-105000D02*
X57183D01*
Y-98700D01*
X60317D01*
G01X59063Y-101745D02*
X57183D01*
G01X63248Y-105000D02*
Y-98700D01*
X66852Y-105000D01*
Y-98700D01*
G01X76005Y-105000D02*
Y-98700D01*
G01X79295D02*
Y-105000D01*
G01Y-101850D02*
X76005D01*
G01X81600Y-98700D02*
X82697Y-105000D01*
X83950Y-98700D01*
X85203Y-105000D01*
X86300Y-98700D01*
G01X88292Y-105000D02*
X90250Y-98700D01*
X92208Y-105000D01*
G01X91503Y-102795D02*
X88997D01*
G01X101362Y-99750D02*
X101832Y-99120D01*
X102380Y-98805D01*
X103007Y-98700D01*
X103790Y-98910D01*
X104338Y-99435D01*
X104495Y-100065D01*
X104417Y-100695D01*
X104103Y-101220D01*
X102537Y-102270D01*
X101832Y-103005D01*
X101362Y-104055D01*
X101205Y-105000D01*
X104495D01*
G01X107348D02*
Y-98700D01*
X110952Y-105000D01*
Y-98700D01*
G01X113727Y-105000D02*
Y-98700D01*
X115293D01*
X115920Y-99015D01*
X116390Y-99435D01*
X116782Y-100065D01*
X117095Y-100800D01*
X117173Y-101850D01*
X117095Y-102900D01*
X116782Y-103635D01*
X116390Y-104265D01*
X115920Y-104685D01*
X115293Y-105000D01*
X113727D01*
G01X126483D02*
Y-98700D01*
X128442D01*
X129068Y-99015D01*
X129460Y-99435D01*
X129617Y-100275D01*
X129460Y-101115D01*
X128990Y-101640D01*
X128442Y-101955D01*
X126483D01*
G01X128442D02*
X129617Y-105000D01*
G01X132627D02*
Y-98700D01*
X134193D01*
X134820Y-99015D01*
X135290Y-99435D01*
X135682Y-100065D01*
X135995Y-100800D01*
X136073Y-101850D01*
X135995Y-102900D01*
X135682Y-103635D01*
X135290Y-104265D01*
X134820Y-104685D01*
X134193Y-105000D01*
X132627D01*
G01X140650Y-105210D02*
X140493Y-105105D01*
Y-104895D01*
X140650Y-104790D01*
X140807Y-104895D01*
Y-105105D01*
X140650Y-105210D01*
G01X202000Y-72000D02*
Y-80000D01*
X206000D01*
G01X213800D02*
Y-74667D01*
G01Y-75600D02*
X213400Y-75067D01*
X212800Y-74800D01*
X212100Y-74667D01*
X211400Y-74933D01*
X210800Y-75467D01*
X210400Y-76267D01*
X210200Y-77333D01*
X210400Y-78400D01*
X210800Y-79200D01*
X211400Y-79733D01*
X212100Y-80000D01*
X212800Y-79867D01*
X213400Y-79467D01*
X213800Y-78934D01*
G01X217900Y-82400D02*
X218500Y-82667D01*
X219300Y-82400D01*
X219800Y-81867D01*
X220200Y-81200D01*
X220800Y-79067D01*
X222100Y-74667D01*
G01X218900D02*
X220800Y-79067D01*
G01X226500Y-76400D02*
X229700D01*
X229400Y-75467D01*
X228900Y-74933D01*
X228200Y-74667D01*
X227500Y-74800D01*
X226900Y-75200D01*
X226500Y-76133D01*
X226300Y-76934D01*
Y-77733D01*
X226500Y-78533D01*
X227000Y-79333D01*
X227600Y-79867D01*
X228300Y-80000D01*
X229000Y-79733D01*
X229700Y-78934D01*
G01X234600Y-80000D02*
Y-74667D01*
G01Y-75733D02*
X235100Y-75200D01*
X235600Y-74800D01*
X236300Y-74667D01*
X236800Y-74800D01*
X237400Y-75200D01*
G01X223400Y-128934D02*
X224200Y-129600D01*
X225100Y-130000D01*
X225900D01*
X226700Y-129600D01*
X227300Y-128934D01*
X227600Y-128000D01*
X227400Y-127067D01*
X226900Y-126267D01*
X226000Y-125733D01*
X224800Y-125467D01*
X224100Y-124933D01*
X223800Y-124000D01*
X224000Y-123067D01*
X224500Y-122400D01*
X225200Y-122000D01*
X225900D01*
X226600Y-122267D01*
X227200Y-122933D01*
G01X235300Y-130000D02*
Y-124667D01*
G01Y-125600D02*
X234900Y-125067D01*
X234300Y-124800D01*
X233600Y-124667D01*
X232900Y-124933D01*
X232300Y-125467D01*
X231900Y-126267D01*
X231700Y-127333D01*
X231900Y-128400D01*
X232300Y-129200D01*
X232900Y-129733D01*
X233600Y-130000D01*
X234300Y-129867D01*
X234900Y-129467D01*
X235300Y-128934D01*
G01X239800Y-130000D02*
Y-124667D01*
G01Y-126000D02*
X240200Y-125333D01*
X240800Y-124800D01*
X241600Y-124667D01*
X242300Y-124800D01*
X242900Y-125333D01*
X243200Y-126267D01*
Y-130000D01*
G01X251300Y-122000D02*
Y-130000D01*
G01Y-128800D02*
X250900Y-129467D01*
X250300Y-129867D01*
X249600Y-130000D01*
X248800Y-129733D01*
X248200Y-129067D01*
X247800Y-128267D01*
X247700Y-127333D01*
X247800Y-126400D01*
X248200Y-125600D01*
X248800Y-124933D01*
X249600Y-124667D01*
X250300Y-124800D01*
X250800Y-125067D01*
X251300Y-125600D01*
G01X255400Y-132400D02*
X256000Y-132667D01*
X256800Y-132400D01*
X257300Y-131867D01*
X257700Y-131200D01*
X258300Y-129067D01*
X259600Y-124667D01*
G01X256400D02*
X258300Y-129067D01*
G01X233000Y-97000D02*
X235500Y-105000D01*
X238000Y-97000D01*
G01X245700Y-97667D02*
X245100Y-97267D01*
X244400Y-97000D01*
X243600D01*
X242700Y-97400D01*
X242000Y-98067D01*
X241500Y-98867D01*
X241100Y-100200D01*
X241000Y-101400D01*
X241200Y-102600D01*
X241500Y-103400D01*
X242100Y-104200D01*
X242800Y-104733D01*
X243500Y-105000D01*
X244200D01*
X244900Y-104733D01*
X245500Y-104333D01*
X246000Y-103800D01*
G01X253700Y-97667D02*
X253100Y-97267D01*
X252400Y-97000D01*
X251600D01*
X250700Y-97400D01*
X250000Y-98067D01*
X249500Y-98867D01*
X249100Y-100200D01*
X249000Y-101400D01*
X249200Y-102600D01*
X249500Y-103400D01*
X250100Y-104200D01*
X250800Y-104733D01*
X251500Y-105000D01*
X252200D01*
X252900Y-104733D01*
X253500Y-104333D01*
X254000Y-103800D01*
G01X259500Y-105000D02*
Y-97000D01*
X258300Y-98600D01*
G01Y-105000D02*
X260700D01*
G01X253300Y-78800D02*
X253900Y-79467D01*
X254600Y-79867D01*
X255500Y-80000D01*
X256400Y-79733D01*
X257100Y-79200D01*
X257600Y-78267D01*
X257700Y-77200D01*
X257500Y-76133D01*
X257000Y-75467D01*
X256300Y-74933D01*
X255600Y-74800D01*
X254900Y-74933D01*
X254000Y-75467D01*
X254300Y-72000D01*
X257000D01*
G01X328600Y-123333D02*
X329200Y-122533D01*
X329900Y-122133D01*
X330700Y-122000D01*
X331700Y-122267D01*
X332400Y-122933D01*
X332600Y-123733D01*
X332500Y-124534D01*
X332100Y-125200D01*
X330100Y-126533D01*
X329200Y-127467D01*
X328600Y-128800D01*
X328400Y-130000D01*
X332600D01*
G01X338500Y-122000D02*
X337700Y-122267D01*
X337100Y-122933D01*
X336700Y-123733D01*
X336400Y-124800D01*
X336300Y-126000D01*
X336400Y-127200D01*
X336700Y-128267D01*
X337100Y-129067D01*
X337700Y-129733D01*
X338500Y-130000D01*
X339300Y-129733D01*
X339900Y-129067D01*
X340300Y-128267D01*
X340600Y-127200D01*
X340700Y-126000D01*
X340600Y-124800D01*
X340300Y-123733D01*
X339900Y-122933D01*
X339300Y-122267D01*
X338500Y-122000D01*
G01X346500Y-130000D02*
Y-122000D01*
X345300Y-123600D01*
G01Y-130000D02*
X347700D01*
G01X352600Y-123333D02*
X353200Y-122533D01*
X353900Y-122133D01*
X354700Y-122000D01*
X355700Y-122267D01*
X356400Y-122933D01*
X356600Y-123733D01*
X356500Y-124534D01*
X356100Y-125200D01*
X354100Y-126533D01*
X353200Y-127467D01*
X352600Y-128800D01*
X352400Y-130000D01*
X356600D01*
G01X360700Y-130267D02*
X364300Y-122000D01*
G01X370500D02*
X369700Y-122267D01*
X369100Y-122933D01*
X368700Y-123733D01*
X368400Y-124800D01*
X368300Y-126000D01*
X368400Y-127200D01*
X368700Y-128267D01*
X369100Y-129067D01*
X369700Y-129733D01*
X370500Y-130000D01*
X371300Y-129733D01*
X371900Y-129067D01*
X372300Y-128267D01*
X372600Y-127200D01*
X372700Y-126000D01*
X372600Y-124800D01*
X372300Y-123733D01*
X371900Y-122933D01*
X371300Y-122267D01*
X370500Y-122000D01*
G01X376800Y-129067D02*
X377500Y-129733D01*
X378300Y-130000D01*
X379100Y-129733D01*
X379800Y-128934D01*
X380300Y-127733D01*
X380500Y-126533D01*
Y-125067D01*
X380300Y-123867D01*
X379800Y-122800D01*
X379200Y-122267D01*
X378500Y-122000D01*
X377700Y-122267D01*
X377100Y-122800D01*
X376700Y-123600D01*
X376500Y-124667D01*
X376700Y-125600D01*
X377200Y-126533D01*
X377800Y-127067D01*
X378500Y-127200D01*
X379300Y-126934D01*
X379900Y-126267D01*
X380500Y-125067D01*
G01X384700Y-130267D02*
X388300Y-122000D01*
G01X392600Y-123333D02*
X393200Y-122533D01*
X393900Y-122133D01*
X394700Y-122000D01*
X395700Y-122267D01*
X396400Y-122933D01*
X396600Y-123733D01*
X396500Y-124534D01*
X396100Y-125200D01*
X394100Y-126533D01*
X393200Y-127467D01*
X392600Y-128800D01*
X392400Y-130000D01*
X396600D01*
G01X402500D02*
X403200Y-129867D01*
X404000Y-129467D01*
X404500Y-128800D01*
X404700Y-127867D01*
X404500Y-126934D01*
X403900Y-126133D01*
X403000Y-125733D01*
X402000D01*
X401400Y-125467D01*
X400900Y-124800D01*
X400700Y-123867D01*
X401000Y-122933D01*
X401700Y-122267D01*
X402500Y-122000D01*
X403300Y-122267D01*
X404000Y-122933D01*
X404300Y-123867D01*
X404100Y-124800D01*
X403600Y-125467D01*
X403000Y-125733D01*
X402000D01*
X401100Y-126133D01*
X400500Y-126934D01*
X400300Y-127867D01*
X400500Y-128800D01*
X401000Y-129467D01*
X401800Y-129867D01*
X402500Y-130000D01*
G01X328300Y-105000D02*
Y-97000D01*
X330300D01*
X331100Y-97400D01*
X331700Y-97933D01*
X332200Y-98733D01*
X332600Y-99667D01*
X332700Y-101000D01*
X332600Y-102333D01*
X332200Y-103267D01*
X331700Y-104067D01*
X331100Y-104600D01*
X330300Y-105000D01*
X328300D01*
G01X336000D02*
X338500Y-97000D01*
X341000Y-105000D01*
G01X340100Y-102200D02*
X336900D01*
G01X346500Y-97000D02*
X345700Y-97267D01*
X345100Y-97933D01*
X344700Y-98733D01*
X344400Y-99800D01*
X344300Y-101000D01*
X344400Y-102200D01*
X344700Y-103267D01*
X345100Y-104067D01*
X345700Y-104733D01*
X346500Y-105000D01*
X347300Y-104733D01*
X347900Y-104067D01*
X348300Y-103267D01*
X348600Y-102200D01*
X348700Y-101000D01*
X348600Y-99800D01*
X348300Y-98733D01*
X347900Y-97933D01*
X347300Y-97267D01*
X346500Y-97000D01*
G01X354500D02*
Y-105000D01*
G01X352200Y-97000D02*
X356800D01*
G01X360600Y-101667D02*
X361300Y-100733D01*
X361900Y-100200D01*
X362700Y-99933D01*
X363400Y-100200D01*
X363900Y-100733D01*
X364300Y-101533D01*
X364400Y-102467D01*
X364300Y-103267D01*
X363900Y-104067D01*
X363300Y-104733D01*
X362600Y-105000D01*
X361800Y-104733D01*
X361100Y-103934D01*
X360700Y-102733D01*
X360600Y-101400D01*
X360800Y-99667D01*
X361100Y-98733D01*
X361600Y-97800D01*
X362300Y-97133D01*
X363000Y-97000D01*
X363700Y-97267D01*
X364200Y-97933D01*
G01X367900Y-105000D02*
Y-97000D01*
X370500Y-103667D01*
X373100Y-97000D01*
Y-105000D01*
G01X378500Y-97000D02*
Y-105000D01*
G01X376200Y-97000D02*
X380800D01*
G01X387300Y-100733D02*
X387700Y-100333D01*
X388000Y-99667D01*
X388200Y-98733D01*
X388000Y-97933D01*
X387600Y-97400D01*
X386900Y-97000D01*
X384200D01*
Y-105000D01*
X387500D01*
X388200Y-104467D01*
X388600Y-103667D01*
X388800Y-102733D01*
X388600Y-101800D01*
X388000Y-101000D01*
X387300Y-100733D01*
X384200D01*
G01X394500Y-105000D02*
X395200Y-104867D01*
X396000Y-104467D01*
X396500Y-103800D01*
X396700Y-102867D01*
X396500Y-101934D01*
X395900Y-101133D01*
X395000Y-100733D01*
X394000D01*
X393400Y-100467D01*
X392900Y-99800D01*
X392700Y-98867D01*
X393000Y-97933D01*
X393700Y-97267D01*
X394500Y-97000D01*
X395300Y-97267D01*
X396000Y-97933D01*
X396300Y-98867D01*
X396100Y-99800D01*
X395600Y-100467D01*
X395000Y-100733D01*
X394000D01*
X393100Y-101133D01*
X392500Y-101934D01*
X392300Y-102867D01*
X392500Y-103800D01*
X393000Y-104467D01*
X393800Y-104867D01*
X394500Y-105000D01*
G01X400300D02*
Y-97000D01*
X402300D01*
X403100Y-97400D01*
X403700Y-97933D01*
X404200Y-98733D01*
X404600Y-99667D01*
X404700Y-101000D01*
X404600Y-102333D01*
X404200Y-103267D01*
X403700Y-104067D01*
X403100Y-104600D01*
X402300Y-105000D01*
X400300D01*
G01X410500Y-97000D02*
X409700Y-97267D01*
X409100Y-97933D01*
X408700Y-98733D01*
X408400Y-99800D01*
X408300Y-101000D01*
X408400Y-102200D01*
X408700Y-103267D01*
X409100Y-104067D01*
X409700Y-104733D01*
X410500Y-105000D01*
X411300Y-104733D01*
X411900Y-104067D01*
X412300Y-103267D01*
X412600Y-102200D01*
X412700Y-101000D01*
X412600Y-99800D01*
X412300Y-98733D01*
X411900Y-97933D01*
X411300Y-97267D01*
X410500Y-97000D01*
G01X350500Y-72000D02*
Y-80000D01*
G01X348200Y-72000D02*
X352800D01*
G01X356600Y-76667D02*
X357300Y-75733D01*
X357900Y-75200D01*
X358700Y-74933D01*
X359400Y-75200D01*
X359900Y-75733D01*
X360300Y-76533D01*
X360400Y-77467D01*
X360300Y-78267D01*
X359900Y-79067D01*
X359300Y-79733D01*
X358600Y-80000D01*
X357800Y-79733D01*
X357100Y-78934D01*
X356700Y-77733D01*
X356600Y-76400D01*
X356800Y-74667D01*
X357100Y-73733D01*
X357600Y-72800D01*
X358300Y-72133D01*
X359000Y-72000D01*
X359700Y-72267D01*
X360200Y-72933D01*
G01X363900Y-80000D02*
Y-72000D01*
X366500Y-78667D01*
X369100Y-72000D01*
Y-80000D01*
G01X371500Y-82667D02*
X377500D01*
G01X380500Y-80000D02*
Y-72000D01*
X382900D01*
X383700Y-72400D01*
X384300Y-73333D01*
X384500Y-74400D01*
X384300Y-75467D01*
X383800Y-76267D01*
X382900Y-76667D01*
X380500D01*
G01X388300Y-80000D02*
Y-72000D01*
X390300D01*
X391100Y-72400D01*
X391700Y-72933D01*
X392200Y-73733D01*
X392600Y-74667D01*
X392700Y-76000D01*
X392600Y-77333D01*
X392200Y-78267D01*
X391700Y-79067D01*
X391100Y-79600D01*
X390300Y-80000D01*
X388300D01*
G01X399300Y-75733D02*
X399700Y-75333D01*
X400000Y-74667D01*
X400200Y-73733D01*
X400000Y-72933D01*
X399600Y-72400D01*
X398900Y-72000D01*
X396200D01*
Y-80000D01*
X399500D01*
X400200Y-79467D01*
X400600Y-78667D01*
X400800Y-77733D01*
X400600Y-76800D01*
X400000Y-76000D01*
X399300Y-75733D01*
X396200D01*
G01X403500Y-82667D02*
X409500D01*
G01X412300Y-80000D02*
Y-72000D01*
X414300D01*
X415100Y-72400D01*
X415700Y-72933D01*
X416200Y-73733D01*
X416600Y-74667D01*
X416700Y-76000D01*
X416600Y-77333D01*
X416200Y-78267D01*
X415700Y-79067D01*
X415100Y-79600D01*
X414300Y-80000D01*
X412300D01*
G01X419500Y-82667D02*
X425500D01*
G01X431300Y-75733D02*
X431700Y-75333D01*
X432000Y-74667D01*
X432200Y-73733D01*
X432000Y-72933D01*
X431600Y-72400D01*
X430900Y-72000D01*
X428200D01*
Y-80000D01*
X431500D01*
X432200Y-79467D01*
X432600Y-78667D01*
X432800Y-77733D01*
X432600Y-76800D01*
X432000Y-76000D01*
X431300Y-75733D01*
X428200D01*
G01X436300Y-80000D02*
Y-72000D01*
X438300D01*
X439100Y-72400D01*
X439700Y-72933D01*
X440200Y-73733D01*
X440600Y-74667D01*
X440700Y-76000D01*
X440600Y-77333D01*
X440200Y-78267D01*
X439700Y-79067D01*
X439100Y-79600D01*
X438300Y-80000D01*
X436300D01*
G01X443300Y-130000D02*
Y-122000D01*
X445300D01*
X446100Y-122400D01*
X446700Y-122933D01*
X447200Y-123733D01*
X447600Y-124667D01*
X447700Y-126000D01*
X447600Y-127333D01*
X447200Y-128267D01*
X446700Y-129067D01*
X446100Y-129600D01*
X445300Y-130000D01*
X443300D01*
G01X473000D02*
Y-122000D01*
X471800Y-123600D01*
G01Y-130000D02*
X474200D01*
G01X478800Y-128800D02*
X479400Y-129467D01*
X480100Y-129867D01*
X481000Y-130000D01*
X481900Y-129733D01*
X482600Y-129200D01*
X483100Y-128267D01*
X483200Y-127200D01*
X483000Y-126133D01*
X482500Y-125467D01*
X481800Y-124933D01*
X481100Y-124800D01*
X480400Y-124933D01*
X479500Y-125467D01*
X479800Y-122000D01*
X482500D01*
M02*
